(kicad_sch
	(version 20250114)
	(generator "eeschema")
	(generator_version "9.0")
	(paper "A3")
	(title_block
		(title "SO-DIMM DDR5 Tester")
		(date "2025-11-26")
		(rev "1.3.0")
		(company "Antmicro Ltd.")
		(comment 1 "www.antmicro.com")
		(comment 2 "Antmicro Ltd")
	)
	(text "User LEDs"
		(exclude_from_sim no)
		(at 13.335 222.25 0)
		(effects
			(font
				(size 2.54 2.54)
				(thickness 0.5994)
				(bold yes)
			)
			(justify left bottom)
		)
	)
	(text "CLK_DIR"
		(exclude_from_sim no)
		(at 201.93 123.825 0)
		(effects
			(font
				(size 1.27 1.27)
			)
			(justify left bottom)
		)
	)
	(text "PRSNT_M2C"
		(exclude_from_sim no)
		(at 199.39 113.665 0)
		(effects
			(font
				(size 1.27 1.27)
			)
			(justify left bottom)
		)
	)
	(text "Probes"
		(exclude_from_sim no)
		(at 207.01 222.25 0)
		(effects
			(font
				(size 2.54 2.54)
				(thickness 0.5994)
				(bold yes)
			)
			(justify left bottom)
		)
	)
	(text "BANK 14"
		(exclude_from_sim no)
		(at 15.24 20.955 0)
		(effects
			(font
				(size 2.9972 2.9972)
				(thickness 0.5994)
				(bold yes)
			)
			(justify left bottom)
		)
	)
	(text "VCCO (HR banks) max: 3.6V"
		(exclude_from_sim no)
		(at 217.17 42.545 0)
		(effects
			(font
				(size 1.27 1.27)
			)
			(justify left bottom)
		)
	)
	(junction
		(at 230.505 252.095)
		(diameter 0)
		(color 0 0 0 0)
	)
	(no_connect
		(at 212.09 140.97)
	)
	(no_connect
		(at 212.09 168.91)
	)
	(no_connect
		(at 212.09 171.45)
	)
	(no_connect
		(at 212.09 153.67)
	)
	(no_connect
		(at 212.09 52.07)
	)
	(no_connect
		(at 212.09 123.19)
	)
	(no_connect
		(at 212.09 115.57)
	)
	(no_connect
		(at 212.09 176.53)
	)
	(no_connect
		(at 212.09 151.13)
	)
	(no_connect
		(at 212.09 156.21)
	)
	(no_connect
		(at 212.09 143.51)
	)
	(no_connect
		(at 212.09 148.59)
	)
	(no_connect
		(at 212.09 110.49)
	)
	(no_connect
		(at 212.09 113.03)
	)
	(no_connect
		(at 212.09 173.99)
	)
	(no_connect
		(at 212.09 161.29)
	)
	(no_connect
		(at 212.09 166.37)
	)
	(no_connect
		(at 212.09 163.83)
	)
	(bus_entry
		(at 132.715 134.62)
		(size 1.27 1.27)
		(stroke
			(width 0)
			(type default)
		)
	)
	(bus_entry
		(at 185.42 68.58)
		(size 1.27 1.27)
		(stroke
			(width 0)
			(type default)
		)
	)
	(bus_entry
		(at 132.715 106.68)
		(size 1.27 1.27)
		(stroke
			(width 0)
			(type default)
		)
	)
	(bus_entry
		(at 166.37 60.96)
		(size 1.27 1.27)
		(stroke
			(width 0)
			(type default)
		)
	)
	(bus_entry
		(at 132.715 137.16)
		(size 1.27 1.27)
		(stroke
			(width 0)
			(type default)
		)
	)
	(bus_entry
		(at 166.37 58.42)
		(size 1.27 1.27)
		(stroke
			(width 0)
			(type default)
		)
	)
	(bus_entry
		(at 132.715 81.28)
		(size 1.27 1.27)
		(stroke
			(width 0)
			(type default)
		)
	)
	(bus_entry
		(at 113.03 157.48)
		(size 1.27 1.27)
		(stroke
			(width 0)
			(type default)
		)
	)
	(bus_entry
		(at 149.225 73.66)
		(size 1.27 1.27)
		(stroke
			(width 0)
			(type default)
		)
	)
	(bus_entry
		(at 149.225 124.46)
		(size 1.27 1.27)
		(stroke
			(width 0)
			(type default)
		)
	)
	(bus_entry
		(at 185.42 71.12)
		(size 1.27 1.27)
		(stroke
			(width 0)
			(type default)
		)
	)
	(bus_entry
		(at 113.03 119.38)
		(size 1.27 1.27)
		(stroke
			(width 0)
			(type default)
		)
	)
	(bus_entry
		(at 132.715 76.2)
		(size 1.27 1.27)
		(stroke
			(width 0)
			(type default)
		)
	)
	(bus_entry
		(at 166.37 53.34)
		(size 1.27 1.27)
		(stroke
			(width 0)
			(type default)
		)
	)
	(bus_entry
		(at 132.715 129.54)
		(size 1.27 1.27)
		(stroke
			(width 0)
			(type default)
		)
	)
	(bus_entry
		(at 132.715 127)
		(size 1.27 1.27)
		(stroke
			(width 0)
			(type default)
		)
	)
	(bus_entry
		(at 166.37 78.74)
		(size 1.27 1.27)
		(stroke
			(width 0)
			(type default)
		)
	)
	(bus_entry
		(at 166.37 55.88)
		(size 1.27 1.27)
		(stroke
			(width 0)
			(type default)
		)
	)
	(wire
		(pts
			(xy 267.081 252.095) (xy 278.13 252.095)
		)
		(stroke
			(width 0)
			(type default)
		)
	)
	(bus
		(pts
			(xy 112.395 117.475) (xy 113.03 118.11)
		)
		(stroke
			(width 0)
			(type default)
		)
	)
	(wire
		(pts
			(xy 67.31 251.46) (xy 67.31 252.73)
		)
		(stroke
			(width 0)
			(type default)
		)
	)
	(wire
		(pts
			(xy 167.64 54.61) (xy 212.09 54.61)
		)
		(stroke
			(width 0)
			(type default)
		)
	)
	(wire
		(pts
			(xy 167.64 57.15) (xy 212.09 57.15)
		)
		(stroke
			(width 0)
			(type default)
		)
	)
	(wire
		(pts
			(xy 67.31 245.11) (xy 67.31 246.38)
		)
		(stroke
			(width 0)
			(type default)
		)
	)
	(wire
		(pts
			(xy 173.99 245.11) (xy 173.99 246.38)
		)
		(stroke
			(width 0)
			(type default)
		)
	)
	(wire
		(pts
			(xy 201.295 92.71) (xy 212.09 92.71)
		)
		(stroke
			(width 0)
			(type default)
		)
	)
	(bus
		(pts
			(xy 146.685 71.755) (xy 148.59 71.755)
		)
		(stroke
			(width 0)
			(type default)
		)
	)
	(wire
		(pts
			(xy 202.565 85.09) (xy 212.09 85.09)
		)
		(stroke
			(width 0)
			(type default)
		)
	)
	(wire
		(pts
			(xy 156.21 261.62) (xy 166.37 261.62)
		)
		(stroke
			(width 0)
			(type default)
		)
	)
	(wire
		(pts
			(xy 201.295 95.25) (xy 212.09 95.25)
		)
		(stroke
			(width 0)
			(type default)
		)
	)
	(bus
		(pts
			(xy 130.175 131.445) (xy 132.08 131.445)
		)
		(stroke
			(width 0)
			(type default)
		)
	)
	(wire
		(pts
			(xy 201.295 105.41) (xy 212.09 105.41)
		)
		(stroke
			(width 0)
			(type default)
		)
	)
	(bus
		(pts
			(xy 163.83 51.435) (xy 165.735 51.435)
		)
		(stroke
			(width 0)
			(type default)
		)
	)
	(bus
		(pts
			(xy 149.225 73.66) (xy 149.225 124.46)
		)
		(stroke
			(width 0)
			(type default)
		)
	)
	(wire
		(pts
			(xy 30.48 251.46) (xy 30.48 252.73)
		)
		(stroke
			(width 0)
			(type default)
		)
	)
	(bus
		(pts
			(xy 132.08 74.295) (xy 132.715 74.93)
		)
		(stroke
			(width 0)
			(type default)
		)
	)
	(wire
		(pts
			(xy 210.82 133.35) (xy 212.09 133.35)
		)
		(stroke
			(width 0)
			(type default)
		)
	)
	(wire
		(pts
			(xy 186.69 69.85) (xy 212.09 69.85)
		)
		(stroke
			(width 0)
			(type default)
		)
	)
	(wire
		(pts
			(xy 173.99 251.46) (xy 173.99 252.73)
		)
		(stroke
			(width 0)
			(type default)
		)
	)
	(wire
		(pts
			(xy 135.89 251.46) (xy 135.89 252.73)
		)
		(stroke
			(width 0)
			(type default)
		)
	)
	(bus
		(pts
			(xy 130.175 74.295) (xy 132.08 74.295)
		)
		(stroke
			(width 0)
			(type default)
		)
	)
	(bus
		(pts
			(xy 132.715 74.93) (xy 132.715 76.2)
		)
		(stroke
			(width 0)
			(type default)
		)
	)
	(wire
		(pts
			(xy 202.565 102.87) (xy 212.09 102.87)
		)
		(stroke
			(width 0)
			(type default)
		)
	)
	(wire
		(pts
			(xy 30.48 265.43) (xy 30.48 266.7)
		)
		(stroke
			(width 0)
			(type default)
		)
	)
	(wire
		(pts
			(xy 30.48 245.11) (xy 30.48 246.38)
		)
		(stroke
			(width 0)
			(type default)
		)
	)
	(bus
		(pts
			(xy 166.37 52.07) (xy 166.37 53.34)
		)
		(stroke
			(width 0)
			(type default)
		)
	)
	(wire
		(pts
			(xy 101.6 236.22) (xy 101.6 237.49)
		)
		(stroke
			(width 0)
			(type default)
		)
	)
	(wire
		(pts
			(xy 101.6 251.46) (xy 101.6 252.73)
		)
		(stroke
			(width 0)
			(type default)
		)
	)
	(wire
		(pts
			(xy 230.505 240.411) (xy 230.505 242.697)
		)
		(stroke
			(width 0)
			(type default)
		)
	)
	(wire
		(pts
			(xy 187.96 64.77) (xy 212.09 64.77)
		)
		(stroke
			(width 0)
			(type default)
		)
	)
	(wire
		(pts
			(xy 167.64 59.69) (xy 212.09 59.69)
		)
		(stroke
			(width 0)
			(type default)
		)
	)
	(bus
		(pts
			(xy 110.49 117.475) (xy 112.395 117.475)
		)
		(stroke
			(width 0)
			(type default)
		)
	)
	(bus
		(pts
			(xy 113.03 118.11) (xy 113.03 119.38)
		)
		(stroke
			(width 0)
			(type default)
		)
	)
	(wire
		(pts
			(xy 202.565 87.63) (xy 212.09 87.63)
		)
		(stroke
			(width 0)
			(type default)
		)
	)
	(bus
		(pts
			(xy 132.08 131.445) (xy 132.715 132.08)
		)
		(stroke
			(width 0)
			(type default)
		)
	)
	(wire
		(pts
			(xy 135.89 245.11) (xy 135.89 246.38)
		)
		(stroke
			(width 0)
			(type default)
		)
	)
	(bus
		(pts
			(xy 132.715 81.28) (xy 132.715 106.68)
		)
		(stroke
			(width 0)
			(type default)
		)
	)
	(wire
		(pts
			(xy 208.28 146.05) (xy 212.09 146.05)
		)
		(stroke
			(width 0)
			(type default)
		)
	)
	(wire
		(pts
			(xy 49.53 261.62) (xy 59.69 261.62)
		)
		(stroke
			(width 0)
			(type default)
		)
	)
	(polyline
		(pts
			(xy 196.85 215.9) (xy 407.67 215.9)
		)
		(stroke
			(width 0)
			(type default)
		)
	)
	(wire
		(pts
			(xy 201.295 100.33) (xy 212.09 100.33)
		)
		(stroke
			(width 0)
			(type default)
		)
	)
	(bus
		(pts
			(xy 182.88 66.675) (xy 184.785 66.675)
		)
		(stroke
			(width 0)
			(type default)
		)
	)
	(wire
		(pts
			(xy 101.6 266.7) (xy 101.6 265.43)
		)
		(stroke
			(width 0)
			(type default)
		)
	)
	(wire
		(pts
			(xy 135.89 265.43) (xy 135.89 266.7)
		)
		(stroke
			(width 0)
			(type default)
		)
	)
	(wire
		(pts
			(xy 150.495 125.73) (xy 212.09 125.73)
		)
		(stroke
			(width 0)
			(type default)
		)
	)
	(bus
		(pts
			(xy 132.715 106.68) (xy 132.715 127)
		)
		(stroke
			(width 0)
			(type default)
		)
	)
	(wire
		(pts
			(xy 133.985 82.55) (xy 212.09 82.55)
		)
		(stroke
			(width 0)
			(type default)
		)
	)
	(wire
		(pts
			(xy 167.64 80.01) (xy 212.09 80.01)
		)
		(stroke
			(width 0)
			(type default)
		)
	)
	(wire
		(pts
			(xy 187.96 67.31) (xy 212.09 67.31)
		)
		(stroke
			(width 0)
			(type default)
		)
	)
	(wire
		(pts
			(xy 12.7 261.62) (xy 22.86 261.62)
		)
		(stroke
			(width 0)
			(type default)
		)
	)
	(wire
		(pts
			(xy 133.985 135.89) (xy 212.09 135.89)
		)
		(stroke
			(width 0)
			(type default)
		)
	)
	(wire
		(pts
			(xy 133.985 138.43) (xy 212.09 138.43)
		)
		(stroke
			(width 0)
			(type default)
		)
	)
	(wire
		(pts
			(xy 173.99 265.43) (xy 173.99 266.7)
		)
		(stroke
			(width 0)
			(type default)
		)
	)
	(bus
		(pts
			(xy 185.42 67.31) (xy 185.42 68.58)
		)
		(stroke
			(width 0)
			(type default)
		)
	)
	(wire
		(pts
			(xy 83.82 261.62) (xy 93.98 261.62)
		)
		(stroke
			(width 0)
			(type default)
		)
	)
	(wire
		(pts
			(xy 210.185 46.99) (xy 212.09 46.99)
		)
		(stroke
			(width 0)
			(type default)
		)
	)
	(bus
		(pts
			(xy 184.785 66.675) (xy 185.42 67.31)
		)
		(stroke
			(width 0)
			(type default)
		)
	)
	(bus
		(pts
			(xy 165.735 51.435) (xy 166.37 52.07)
		)
		(stroke
			(width 0)
			(type default)
		)
	)
	(bus
		(pts
			(xy 132.715 134.62) (xy 132.715 137.16)
		)
		(stroke
			(width 0)
			(type default)
		)
	)
	(bus
		(pts
			(xy 113.03 119.38) (xy 113.03 157.48)
		)
		(stroke
			(width 0)
			(type default)
		)
	)
	(wire
		(pts
			(xy 230.505 247.777) (xy 230.505 252.095)
		)
		(stroke
			(width 0)
			(type default)
		)
	)
	(bus
		(pts
			(xy 132.715 76.2) (xy 132.715 81.28)
		)
		(stroke
			(width 0)
			(type default)
		)
	)
	(wire
		(pts
			(xy 230.505 255.143) (xy 230.505 252.095)
		)
		(stroke
			(width 0)
			(type default)
		)
	)
	(bus
		(pts
			(xy 132.715 132.08) (xy 132.715 134.62)
		)
		(stroke
			(width 0)
			(type default)
		)
	)
	(wire
		(pts
			(xy 133.985 77.47) (xy 212.09 77.47)
		)
		(stroke
			(width 0)
			(type default)
		)
	)
	(wire
		(pts
			(xy 114.3 158.75) (xy 212.09 158.75)
		)
		(stroke
			(width 0)
			(type default)
		)
	)
	(wire
		(pts
			(xy 210.82 118.11) (xy 212.09 118.11)
		)
		(stroke
			(width 0)
			(type default)
		)
	)
	(wire
		(pts
			(xy 186.69 72.39) (xy 212.09 72.39)
		)
		(stroke
			(width 0)
			(type default)
		)
	)
	(bus
		(pts
			(xy 166.37 60.96) (xy 166.37 78.74)
		)
		(stroke
			(width 0)
			(type default)
		)
	)
	(bus
		(pts
			(xy 148.59 71.755) (xy 149.225 72.39)
		)
		(stroke
			(width 0)
			(type default)
		)
	)
	(bus
		(pts
			(xy 149.225 72.39) (xy 149.225 73.66)
		)
		(stroke
			(width 0)
			(type default)
		)
	)
	(polyline
		(pts
			(xy 12.065 215.9) (xy 196.85 215.9)
		)
		(stroke
			(width 0)
			(type default)
		)
	)
	(wire
		(pts
			(xy 114.3 120.65) (xy 212.09 120.65)
		)
		(stroke
			(width 0)
			(type default)
		)
	)
	(wire
		(pts
			(xy 67.31 265.43) (xy 67.31 266.7)
		)
		(stroke
			(width 0)
			(type default)
		)
	)
	(wire
		(pts
			(xy 225.425 252.095) (xy 230.505 252.095)
		)
		(stroke
			(width 0)
			(type default)
		)
	)
	(wire
		(pts
			(xy 30.48 236.22) (xy 30.48 237.49)
		)
		(stroke
			(width 0)
			(type default)
		)
	)
	(bus
		(pts
			(xy 185.42 68.58) (xy 185.42 71.12)
		)
		(stroke
			(width 0)
			(type default)
		)
	)
	(polyline
		(pts
			(xy 205.105 285.115) (xy 205.105 215.9)
		)
		(stroke
			(width 0)
			(type default)
		)
	)
	(wire
		(pts
			(xy 210.185 45.085) (xy 210.185 46.99)
		)
		(stroke
			(width 0)
			(type default)
		)
	)
	(bus
		(pts
			(xy 166.37 53.34) (xy 166.37 55.88)
		)
		(stroke
			(width 0)
			(type default)
		)
	)
	(bus
		(pts
			(xy 166.37 55.88) (xy 166.37 58.42)
		)
		(stroke
			(width 0)
			(type default)
		)
	)
	(wire
		(pts
			(xy 133.985 128.27) (xy 212.09 128.27)
		)
		(stroke
			(width 0)
			(type default)
		)
	)
	(wire
		(pts
			(xy 167.64 62.23) (xy 212.09 62.23)
		)
		(stroke
			(width 0)
			(type default)
		)
	)
	(bus
		(pts
			(xy 166.37 58.42) (xy 166.37 60.96)
		)
		(stroke
			(width 0)
			(type default)
		)
	)
	(wire
		(pts
			(xy 67.31 236.22) (xy 67.31 237.49)
		)
		(stroke
			(width 0)
			(type default)
		)
	)
	(wire
		(pts
			(xy 135.89 236.22) (xy 135.89 237.49)
		)
		(stroke
			(width 0)
			(type default)
		)
	)
	(wire
		(pts
			(xy 230.505 252.095) (xy 238.125 252.095)
		)
		(stroke
			(width 0)
			(type default)
		)
	)
	(wire
		(pts
			(xy 202.565 97.79) (xy 212.09 97.79)
		)
		(stroke
			(width 0)
			(type default)
		)
	)
	(wire
		(pts
			(xy 118.11 261.62) (xy 128.27 261.62)
		)
		(stroke
			(width 0)
			(type default)
		)
	)
	(bus
		(pts
			(xy 132.715 127) (xy 132.715 129.54)
		)
		(stroke
			(width 0)
			(type default)
		)
	)
	(wire
		(pts
			(xy 150.495 74.93) (xy 212.09 74.93)
		)
		(stroke
			(width 0)
			(type default)
		)
	)
	(wire
		(pts
			(xy 133.985 107.95) (xy 212.09 107.95)
		)
		(stroke
			(width 0)
			(type default)
		)
	)
	(wire
		(pts
			(xy 202.565 90.17) (xy 212.09 90.17)
		)
		(stroke
			(width 0)
			(type default)
		)
	)
	(wire
		(pts
			(xy 133.985 130.81) (xy 212.09 130.81)
		)
		(stroke
			(width 0)
			(type default)
		)
	)
	(wire
		(pts
			(xy 173.99 236.22) (xy 173.99 237.49)
		)
		(stroke
			(width 0)
			(type default)
		)
	)
	(wire
		(pts
			(xy 101.6 245.11) (xy 101.6 246.38)
		)
		(stroke
			(width 0)
			(type default)
		)
	)
	(label "FPGA_DDR.SDA"
		(at 150.495 74.93 0)
		(effects
			(font
				(size 1.27 1.27)
			)
			(justify left bottom)
		)
	)
	(label "EMCCLK"
		(at 187.96 67.31 0)
		(effects
			(font
				(size 1.27 1.27)
			)
			(justify left bottom)
		)
	)
	(label "USR_LED3"
		(at 83.82 261.62 0)
		(effects
			(font
				(size 1.27 1.27)
			)
			(justify left bottom)
		)
	)
	(label "USR_LED2"
		(at 202.565 90.17 0)
		(effects
			(font
				(size 1.27 1.27)
			)
			(justify left bottom)
		)
	)
	(label "FLASH.IO1"
		(at 167.64 57.15 0)
		(effects
			(font
				(size 1.27 1.27)
			)
			(justify left bottom)
		)
	)
	(label "FPGA_PWR.SCL"
		(at 114.3 158.75 0)
		(effects
			(font
				(size 1.27 1.27)
			)
			(justify left bottom)
		)
	)
	(label "EMCCLK"
		(at 278.13 252.095 180)
		(effects
			(font
				(size 1.27 1.27)
			)
			(justify right bottom)
		)
	)
	(label "USR_LED5"
		(at 202.565 97.79 0)
		(effects
			(font
				(size 1.27 1.27)
			)
			(justify left bottom)
		)
	)
	(label "UART1.RX"
		(at 186.69 72.39 0)
		(effects
			(font
				(size 1.27 1.27)
			)
			(justify left bottom)
		)
	)
	(label "FLASH.IO0"
		(at 167.64 54.61 0)
		(effects
			(font
				(size 1.27 1.27)
			)
			(justify left bottom)
		)
	)
	(label "FPGA_DDR.SCL"
		(at 150.495 125.73 0)
		(effects
			(font
				(size 1.27 1.27)
			)
			(justify left bottom)
		)
	)
	(label "USR_LED1"
		(at 12.7 261.62 0)
		(effects
			(font
				(size 1.27 1.27)
			)
			(justify left bottom)
		)
	)
	(label "USR_LED3"
		(at 202.565 102.87 0)
		(effects
			(font
				(size 1.27 1.27)
			)
			(justify left bottom)
		)
	)
	(label "USR_LED1"
		(at 202.565 85.09 0)
		(effects
			(font
				(size 1.27 1.27)
			)
			(justify left bottom)
		)
	)
	(label "PUDC_B"
		(at 238.125 252.095 180)
		(effects
			(font
				(size 1.27 1.27)
			)
			(justify right bottom)
		)
	)
	(label "FLASH.~{CS}"
		(at 167.64 80.01 0)
		(effects
			(font
				(size 1.27 1.27)
			)
			(justify left bottom)
		)
	)
	(label "FPGA_PWR.SDA"
		(at 114.3 120.65 0)
		(effects
			(font
				(size 1.27 1.27)
			)
			(justify left bottom)
		)
	)
	(label "USR_LED4"
		(at 202.565 87.63 0)
		(effects
			(font
				(size 1.27 1.27)
			)
			(justify left bottom)
		)
	)
	(label "AUX.RST"
		(at 133.985 130.81 0)
		(effects
			(font
				(size 1.27 1.27)
			)
			(justify left bottom)
		)
	)
	(label "UART0.TX"
		(at 133.985 138.43 0)
		(effects
			(font
				(size 1.27 1.27)
			)
			(justify left bottom)
		)
	)
	(label "FLASH.IO2"
		(at 167.64 59.69 0)
		(effects
			(font
				(size 1.27 1.27)
			)
			(justify left bottom)
		)
	)
	(label "AUX.TCK"
		(at 133.985 82.55 0)
		(effects
			(font
				(size 1.27 1.27)
			)
			(justify left bottom)
		)
	)
	(label "UART0.RX"
		(at 133.985 135.89 0)
		(effects
			(font
				(size 1.27 1.27)
			)
			(justify left bottom)
		)
	)
	(label "AUX.TMS"
		(at 133.985 128.27 0)
		(effects
			(font
				(size 1.27 1.27)
			)
			(justify left bottom)
		)
	)
	(label "FLASH.IO3"
		(at 167.64 62.23 0)
		(effects
			(font
				(size 1.27 1.27)
			)
			(justify left bottom)
		)
	)
	(label "USR_LED5"
		(at 156.21 261.62 0)
		(effects
			(font
				(size 1.27 1.27)
			)
			(justify left bottom)
		)
	)
	(label "PUDC_B"
		(at 187.96 64.77 0)
		(effects
			(font
				(size 1.27 1.27)
			)
			(justify left bottom)
		)
	)
	(label "USR_LED4"
		(at 118.11 261.62 0)
		(effects
			(font
				(size 1.27 1.27)
			)
			(justify left bottom)
		)
	)
	(label "USR_LED2"
		(at 49.53 261.62 0)
		(effects
			(font
				(size 1.27 1.27)
			)
			(justify left bottom)
		)
	)
	(label "UART1.TX"
		(at 186.69 69.85 0)
		(effects
			(font
				(size 1.27 1.27)
			)
			(justify left bottom)
		)
	)
	(label "AUX.TDI"
		(at 133.985 107.95 0)
		(effects
			(font
				(size 1.27 1.27)
			)
			(justify left bottom)
		)
	)
	(label "AUX.TDO"
		(at 133.985 77.47 0)
		(effects
			(font
				(size 1.27 1.27)
			)
			(justify left bottom)
		)
	)
	(global_label "HOT_SWAP_YELLOW"
		(shape input)
		(at 201.295 92.71 180)
		(fields_autoplaced yes)
		(effects
			(font
				(size 1.27 1.27)
			)
			(justify right)
		)
		(property "Intersheetrefs" "${INTERSHEET_REFS}"
			(at 181.3118 92.6306 0)
			(effects
				(font
					(size 1.27 1.27)
				)
				(justify right)
			)
		)
	)
	(global_label "FPGA_POWER_OFF"
		(shape input)
		(at 210.82 118.11 180)
		(fields_autoplaced yes)
		(effects
			(font
				(size 1.27 1.27)
			)
			(justify right)
		)
		(property "Intersheetrefs" "${INTERSHEET_REFS}"
			(at 191.8648 118.0306 0)
			(effects
				(font
					(size 1.27 1.27)
				)
				(justify right)
			)
		)
	)
	(global_label "FPGA_POWER_CYCLE"
		(shape input)
		(at 210.82 133.35 180)
		(fields_autoplaced yes)
		(effects
			(font
				(size 1.27 1.27)
			)
			(justify right)
		)
		(property "Intersheetrefs" "${INTERSHEET_REFS}"
			(at 189.5668 133.2706 0)
			(effects
				(font
					(size 1.27 1.27)
				)
				(justify right)
			)
		)
	)
	(global_label "HOT_SWAP_GREEN"
		(shape input)
		(at 201.295 105.41 180)
		(fields_autoplaced yes)
		(effects
			(font
				(size 1.27 1.27)
			)
			(justify right)
		)
		(property "Intersheetrefs" "${INTERSHEET_REFS}"
			(at 182.2189 105.3306 0)
			(effects
				(font
					(size 1.27 1.27)
				)
				(justify right)
			)
		)
	)
	(global_label "HOT_SWAP_RED"
		(shape input)
		(at 201.295 95.25 180)
		(fields_autoplaced yes)
		(effects
			(font
				(size 1.27 1.27)
			)
			(justify right)
		)
		(property "Intersheetrefs" "${INTERSHEET_REFS}"
			(at 184.6984 95.1706 0)
			(effects
				(font
					(size 1.27 1.27)
				)
				(justify right)
			)
		)
	)
	(global_label "HOT_SWAP_BUTTON"
		(shape input)
		(at 201.295 100.33 180)
		(fields_autoplaced yes)
		(effects
			(font
				(size 1.27 1.27)
			)
			(justify right)
		)
		(property "Intersheetrefs" "${INTERSHEET_REFS}"
			(at 181.1908 100.4094 0)
			(effects
				(font
					(size 1.27 1.27)
				)
				(justify right)
			)
		)
	)
	(global_label "FAN_PWM"
		(shape input)
		(at 208.28 146.05 180)
		(fields_autoplaced yes)
		(effects
			(font
				(size 1.27 1.27)
			)
			(justify right)
		)
		(property "Intersheetrefs" "${INTERSHEET_REFS}"
			(at 197.3077 145.9706 0)
			(effects
				(font
					(size 1.27 1.27)
				)
				(justify right)
			)
		)
	)
	(hierarchical_label "AUX{JTAG}"
		(shape bidirectional)
		(at 130.175 74.295 180)
		(effects
			(font
				(size 1.27 1.27)
			)
			(justify right)
		)
	)
	(hierarchical_label "FPGA_DDR{I^{2}C}"
		(shape bidirectional)
		(at 146.685 71.755 180)
		(effects
			(font
				(size 1.27 1.27)
			)
			(justify right)
		)
	)
	(hierarchical_label "FLASH{QSPI}"
		(shape bidirectional)
		(at 163.83 51.435 180)
		(effects
			(font
				(size 1.27 1.27)
			)
			(justify right)
		)
	)
	(hierarchical_label "UART1{UART}"
		(shape bidirectional)
		(at 182.88 66.675 180)
		(effects
			(font
				(size 1.27 1.27)
			)
			(justify right)
		)
	)
	(hierarchical_label "UART0{UART}"
		(shape bidirectional)
		(at 130.175 131.445 180)
		(effects
			(font
				(size 1.27 1.27)
			)
			(justify right)
		)
	)
	(hierarchical_label "FPGA_PWR{I^{2}C}"
		(shape bidirectional)
		(at 110.49 117.475 180)
		(effects
			(font
				(size 1.27 1.27)
			)
			(justify right)
		)
	)
	(symbol
		(lib_id "antmicroTestPoints:TP_1mm_SMD")
		(at 267.081 252.095 180)
		(unit 1)
		(exclude_from_sim no)
		(in_bom yes)
		(on_board yes)
		(dnp no)
		(fields_autoplaced yes)
		(property "Reference" "TP24"
			(at 263.906 249.301 0)
			(effects
				(font
					(size 1.27 1.27)
				)
			)
		)
		(property "Value" "TP_1mm_SMD"
			(at 251.841 244.475 0)
			(effects
				(font
					(size 1.27 1.27)
					(thickness 0.15)
				)
				(justify left bottom)
				(hide yes)
			)
		)
		(property "Footprint" "antmicro-footprints:TP_SMD_1mm"
			(at 251.841 241.935 0)
			(effects
				(font
					(size 1.27 1.27)
					(thickness 0.15)
				)
				(justify left bottom)
				(hide yes)
			)
		)
		(property "Datasheet" ""
			(at 251.841 239.395 0)
			(effects
				(font
					(size 1.27 1.27)
					(thickness 0.15)
				)
				(justify left bottom)
				(hide yes)
			)
		)
		(property "Description" ""
			(at 267.081 252.095 0)
			(effects
				(font
					(size 1.27 1.27)
				)
			)
		)
		(property "MPN" ""
			(at 267.081 252.095 0)
			(effects
				(font
					(size 1.27 1.27)
				)
				(hide yes)
			)
		)
		(property "Manufacturer" ""
			(at 267.081 252.095 0)
			(effects
				(font
					(size 1.27 1.27)
				)
				(hide yes)
			)
		)
		(property "Author" "Antmicro"
			(at 251.841 236.855 0)
			(effects
				(font
					(size 1.27 1.27)
					(thickness 0.15)
				)
				(justify left bottom)
				(hide yes)
			)
		)
		(property "License" "Apache-2.0"
			(at 251.841 234.315 0)
			(effects
				(font
					(size 1.27 1.27)
					(thickness 0.15)
				)
				(justify left bottom)
				(hide yes)
			)
		)
		(pin "1"
		)
		(instances
			(project "sodimm-ddr5-tester"
				(path ""
					(reference "TP24")
					(unit 1)
				)
			)
		)
	)
	(symbol
		(lib_id "antmicroResistors0402:R_330R_0402")
		(at 135.89 246.38 270)
		(unit 1)
		(exclude_from_sim no)
		(in_bom yes)
		(on_board yes)
		(dnp no)
		(fields_autoplaced yes)
		(property "Reference" "R45"
			(at 137.541 248.0894 90)
			(effects
				(font
					(size 1.27 1.27)
				)
				(justify left)
			)
		)
		(property "Value" "R_330R_0402"
			(at 123.19 266.7 0)
			(effects
				(font
					(size 1.27 1.27)
					(thickness 0.15)
				)
				(justify left bottom)
				(hide yes)
			)
		)
		(property "Footprint" "antmicro-footprints:R_0402_1005Metric"
			(at 120.65 266.7 0)
			(effects
				(font
					(size 1.27 1.27)
					(thickness 0.15)
				)
				(justify left bottom)
				(hide yes)
			)
		)
		(property "Datasheet" "https://www.bourns.com/docs/product-datasheets/cr.pdf"
			(at 118.11 266.7 0)
			(effects
				(font
					(size 1.27 1.27)
					(thickness 0.15)
				)
				(justify left bottom)
				(hide yes)
			)
		)
		(property "Description" ""
			(at 135.89 246.38 0)
			(effects
				(font
					(size 1.27 1.27)
				)
			)
		)
		(property "Manufacturer" "Bourns"
			(at 113.03 266.7 0)
			(effects
				(font
					(size 1.27 1.27)
					(thickness 0.15)
				)
				(justify left bottom)
				(hide yes)
			)
		)
		(property "MPN" "CR0402-FX-3300GLF"
			(at 115.57 266.7 0)
			(effects
				(font
					(size 1.27 1.27)
					(thickness 0.15)
				)
				(justify left bottom)
				(hide yes)
			)
		)
		(property "Val" "330R"
			(at 137.541 250.6197 90)
			(effects
				(font
					(size 1.27 1.27)
					(thickness 0.15)
				)
				(justify left)
			)
		)
		(property "License" "Apache-2.0"
			(at 110.49 266.7 0)
			(effects
				(font
					(size 1.27 1.27)
					(thickness 0.15)
				)
				(justify left bottom)
				(hide yes)
			)
		)
		(property "Author" "Antmicro"
			(at 107.95 266.7 0)
			(effects
				(font
					(size 1.27 1.27)
					(thickness 0.15)
				)
				(justify left bottom)
				(hide yes)
			)
		)
		(property "Tolerance" "1%"
			(at 125.73 266.7 0)
			(effects
				(font
					(size 1.27 1.27)
				)
				(justify left bottom)
				(hide yes)
			)
		)
		(pin "1"
		)
		(pin "2"
		)
		(instances
			(project "sodimm-ddr5-tester"
				(path ""
					(reference "R45")
					(unit 1)
				)
			)
		)
	)
	(symbol
		(lib_id "antmicroResistors0402:R_100R_0402")
		(at 230.505 255.143 270)
		(unit 1)
		(exclude_from_sim no)
		(in_bom no)
		(on_board yes)
		(dnp yes)
		(property "Reference" "R22"
			(at 233.045 256.413 90)
			(effects
				(font
					(size 1.27 1.27)
				)
				(justify left)
			)
		)
		(property "Value" "R_100R_0402"
			(at 217.805 275.463 0)
			(effects
				(font
					(size 1.27 1.27)
					(thickness 0.15)
				)
				(justify left bottom)
				(hide yes)
			)
		)
		(property "Footprint" "antmicro-footprints:R_0402_1005Metric"
			(at 215.265 275.463 0)
			(effects
				(font
					(size 1.27 1.27)
					(thickness 0.15)
				)
				(justify left bottom)
				(hide yes)
			)
		)
		(property "Datasheet" "https://www.bourns.com/docs/product-datasheets/cr.pdf"
			(at 212.725 275.463 0)
			(effects
				(font
					(size 1.27 1.27)
					(thickness 0.15)
				)
				(justify left bottom)
				(hide yes)
			)
		)
		(property "Description" ""
			(at 230.505 255.143 0)
			(effects
				(font
					(size 1.27 1.27)
				)
			)
		)
		(property "Manufacturer" "Bourns"
			(at 207.645 275.463 0)
			(effects
				(font
					(size 1.27 1.27)
					(thickness 0.15)
				)
				(justify left bottom)
				(hide yes)
			)
		)
		(property "MPN" "CR0402-FX-1000GLF"
			(at 210.185 275.463 0)
			(effects
				(font
					(size 1.27 1.27)
					(thickness 0.15)
				)
				(justify left bottom)
				(hide yes)
			)
		)
		(property "Val" "100R"
			(at 233.045 259.5879 90)
			(effects
				(font
					(size 1.27 1.27)
					(thickness 0.15)
				)
				(justify left)
			)
		)
		(property "License" "Apache-2.0"
			(at 205.105 275.463 0)
			(effects
				(font
					(size 1.27 1.27)
					(thickness 0.15)
				)
				(justify left bottom)
				(hide yes)
			)
		)
		(property "Author" "Antmicro"
			(at 202.565 275.463 0)
			(effects
				(font
					(size 1.27 1.27)
					(thickness 0.15)
				)
				(justify left bottom)
				(hide yes)
			)
		)
		(property "Tolerance" "1%"
			(at 220.345 275.463 0)
			(effects
				(font
					(size 1.27 1.27)
				)
				(justify left bottom)
				(hide yes)
			)
		)
		(pin "1"
		)
		(pin "2"
		)
		(instances
			(project "sodimm-ddr5-tester"
				(path ""
					(reference "R22")
					(unit 1)
				)
			)
		)
	)
	(symbol
		(lib_id "antmicroTransistorsFETsMOSFETsSingle:BSS138PW,115")
		(at 22.86 261.62 0)
		(unit 1)
		(exclude_from_sim no)
		(in_bom yes)
		(on_board yes)
		(dnp no)
		(fields_autoplaced yes)
		(property "Reference" "Q4"
			(at 34.29 257.81 0)
			(effects
				(font
					(size 1.27 1.27)
					(thickness 0.15)
				)
				(justify left)
			)
		)
		(property "Value" "BSS138PW,115"
			(at 45.72 270.51 0)
			(effects
				(font
					(size 1.27 1.27)
					(thickness 0.15)
				)
				(justify left bottom)
				(hide yes)
			)
		)
		(property "Footprint" "antmicro-footprints:SC70-3"
			(at 45.72 273.05 0)
			(effects
				(font
					(size 1.27 1.27)
					(thickness 0.15)
				)
				(justify left bottom)
				(hide yes)
			)
		)
		(property "Datasheet" "https://assets.nexperia.com/documents/data-sheet/BSS138PW.pdf"
			(at 45.72 275.59 0)
			(effects
				(font
					(size 1.27 1.27)
					(thickness 0.15)
				)
				(justify left bottom)
				(hide yes)
			)
		)
		(property "Description" "Power MOSFET, N Channel, 60 V, 320 mA, 0.9 ohm, SOT-323, Surface Mount"
			(at 45.72 288.29 0)
			(effects
				(font
					(size 1.27 1.27)
				)
				(justify left bottom)
				(hide yes)
			)
		)
		(property "MPN" "BSS138PW,115"
			(at 34.29 260.35 0)
			(effects
				(font
					(size 1.27 1.27)
					(thickness 0.15)
				)
				(justify left)
			)
		)
		(property "Manufacturer" "Nexperia"
			(at 45.72 280.67 0)
			(effects
				(font
					(size 1.27 1.27)
					(thickness 0.15)
				)
				(justify left bottom)
				(hide yes)
			)
		)
		(property "Author" "Antmicro"
			(at 45.72 283.21 0)
			(effects
				(font
					(size 1.27 1.27)
					(thickness 0.15)
				)
				(justify left bottom)
				(hide yes)
			)
		)
		(property "License" "Apache-2.0"
			(at 45.72 285.75 0)
			(effects
				(font
					(size 1.27 1.27)
					(thickness 0.15)
				)
				(justify left bottom)
				(hide yes)
			)
		)
		(pin "3"
		)
		(pin "2"
		)
		(pin "1"
		)
		(instances
			(project "sodimm-ddr5-tester"
				(path ""
					(reference "Q4")
					(unit 1)
				)
			)
		)
	)
	(symbol
		(lib_id "antmicropower:+3V3")
		(at 210.185 45.085 0)
		(unit 1)
		(exclude_from_sim no)
		(in_bom yes)
		(on_board yes)
		(dnp no)
		(fields_autoplaced yes)
		(property "Reference" "#PWR0237"
			(at 210.185 48.895 0)
			(effects
				(font
					(size 1.27 1.27)
				)
				(hide yes)
			)
		)
		(property "Value" "+3V3"
			(at 207.01 42.545 0)
			(effects
				(font
					(size 1.27 1.27)
					(thickness 0.15)
				)
				(justify left bottom)
			)
		)
		(property "Footprint" ""
			(at 225.425 52.705 0)
			(effects
				(font
					(size 1.27 1.27)
					(thickness 0.15)
				)
				(justify left bottom)
				(hide yes)
			)
		)
		(property "Datasheet" ""
			(at 225.425 55.245 0)
			(effects
				(font
					(size 1.27 1.27)
					(thickness 0.15)
				)
				(justify left bottom)
				(hide yes)
			)
		)
		(property "Description" ""
			(at 210.185 45.085 0)
			(effects
				(font
					(size 1.27 1.27)
				)
			)
		)
		(property "Author" "Antmicro"
			(at 225.425 47.625 0)
			(effects
				(font
					(size 1.27 1.27)
					(thickness 0.15)
				)
				(justify left bottom)
				(hide yes)
			)
		)
		(property "License" "Apache-2.0"
			(at 225.425 50.165 0)
			(effects
				(font
					(size 1.27 1.27)
					(thickness 0.15)
				)
				(justify left bottom)
				(hide yes)
			)
		)
		(pin "1"
		)
		(instances
			(project "sodimm-ddr5-tester"
				(path ""
					(reference "#PWR0237")
					(unit 1)
				)
			)
		)
	)
	(symbol
		(lib_id "antmicroResistors0402:R_330R_0402")
		(at 173.99 246.38 270)
		(unit 1)
		(exclude_from_sim no)
		(in_bom yes)
		(on_board yes)
		(dnp no)
		(fields_autoplaced yes)
		(property "Reference" "R46"
			(at 175.641 248.0894 90)
			(effects
				(font
					(size 1.27 1.27)
				)
				(justify left)
			)
		)
		(property "Value" "R_330R_0402"
			(at 161.29 266.7 0)
			(effects
				(font
					(size 1.27 1.27)
					(thickness 0.15)
				)
				(justify left bottom)
				(hide yes)
			)
		)
		(property "Footprint" "antmicro-footprints:R_0402_1005Metric"
			(at 158.75 266.7 0)
			(effects
				(font
					(size 1.27 1.27)
					(thickness 0.15)
				)
				(justify left bottom)
				(hide yes)
			)
		)
		(property "Datasheet" "https://www.bourns.com/docs/product-datasheets/cr.pdf"
			(at 156.21 266.7 0)
			(effects
				(font
					(size 1.27 1.27)
					(thickness 0.15)
				)
				(justify left bottom)
				(hide yes)
			)
		)
		(property "Description" ""
			(at 173.99 246.38 0)
			(effects
				(font
					(size 1.27 1.27)
				)
			)
		)
		(property "Manufacturer" "Bourns"
			(at 151.13 266.7 0)
			(effects
				(font
					(size 1.27 1.27)
					(thickness 0.15)
				)
				(justify left bottom)
				(hide yes)
			)
		)
		(property "MPN" "CR0402-FX-3300GLF"
			(at 153.67 266.7 0)
			(effects
				(font
					(size 1.27 1.27)
					(thickness 0.15)
				)
				(justify left bottom)
				(hide yes)
			)
		)
		(property "Val" "330R"
			(at 175.641 250.6197 90)
			(effects
				(font
					(size 1.27 1.27)
					(thickness 0.15)
				)
				(justify left)
			)
		)
		(property "License" "Apache-2.0"
			(at 148.59 266.7 0)
			(effects
				(font
					(size 1.27 1.27)
					(thickness 0.15)
				)
				(justify left bottom)
				(hide yes)
			)
		)
		(property "Author" "Antmicro"
			(at 146.05 266.7 0)
			(effects
				(font
					(size 1.27 1.27)
					(thickness 0.15)
				)
				(justify left bottom)
				(hide yes)
			)
		)
		(property "Tolerance" "1%"
			(at 163.83 266.7 0)
			(effects
				(font
					(size 1.27 1.27)
				)
				(justify left bottom)
				(hide yes)
			)
		)
		(pin "1"
		)
		(pin "2"
		)
		(instances
			(project "sodimm-ddr5-tester"
				(path ""
					(reference "R46")
					(unit 1)
				)
			)
		)
	)
	(symbol
		(lib_id "antmicropower:+3V3")
		(at 30.48 236.22 0)
		(unit 1)
		(exclude_from_sim no)
		(in_bom yes)
		(on_board yes)
		(dnp no)
		(fields_autoplaced yes)
		(property "Reference" "#PWR0427"
			(at 30.48 240.03 0)
			(effects
				(font
					(size 1.27 1.27)
				)
				(hide yes)
			)
		)
		(property "Value" "+3V3"
			(at 27.305 233.68 0)
			(effects
				(font
					(size 1.27 1.27)
					(thickness 0.15)
				)
				(justify left bottom)
			)
		)
		(property "Footprint" ""
			(at 45.72 243.84 0)
			(effects
				(font
					(size 1.27 1.27)
					(thickness 0.15)
				)
				(justify left bottom)
				(hide yes)
			)
		)
		(property "Datasheet" ""
			(at 45.72 246.38 0)
			(effects
				(font
					(size 1.27 1.27)
					(thickness 0.15)
				)
				(justify left bottom)
				(hide yes)
			)
		)
		(property "Description" ""
			(at 30.48 236.22 0)
			(effects
				(font
					(size 1.27 1.27)
				)
			)
		)
		(property "Author" "Antmicro"
			(at 45.72 238.76 0)
			(effects
				(font
					(size 1.27 1.27)
					(thickness 0.15)
				)
				(justify left bottom)
				(hide yes)
			)
		)
		(property "License" "Apache-2.0"
			(at 45.72 241.3 0)
			(effects
				(font
					(size 1.27 1.27)
					(thickness 0.15)
				)
				(justify left bottom)
				(hide yes)
			)
		)
		(pin "1"
		)
		(instances
			(project "sodimm-ddr5-tester"
				(path ""
					(reference "#PWR0427")
					(unit 1)
				)
			)
		)
	)
	(symbol
		(lib_id "antmicropower:GND")
		(at 30.48 266.7 0)
		(unit 1)
		(exclude_from_sim no)
		(in_bom yes)
		(on_board yes)
		(dnp no)
		(property "Reference" "#PWR0428"
			(at 30.48 273.05 0)
			(effects
				(font
					(size 1.27 1.27)
				)
				(hide yes)
			)
		)
		(property "Value" "GND"
			(at 28.956 270.637 0)
			(effects
				(font
					(size 1.27 1.27)
					(thickness 0.15)
				)
				(justify left)
			)
		)
		(property "Footprint" ""
			(at 39.37 274.32 0)
			(effects
				(font
					(size 1.27 1.27)
					(thickness 0.15)
				)
				(justify left bottom)
				(hide yes)
			)
		)
		(property "Datasheet" ""
			(at 39.37 279.4 0)
			(effects
				(font
					(size 1.27 1.27)
					(thickness 0.15)
				)
				(justify left bottom)
				(hide yes)
			)
		)
		(property "Description" ""
			(at 39.37 281.94 0)
			(effects
				(font
					(size 1.27 1.27)
				)
				(justify left bottom)
				(hide yes)
			)
		)
		(property "Author" "Antmicro"
			(at 39.37 274.32 0)
			(effects
				(font
					(size 1.27 1.27)
					(thickness 0.15)
				)
				(justify left bottom)
				(hide yes)
			)
		)
		(property "License" "Apache-2.0"
			(at 39.37 276.86 0)
			(effects
				(font
					(size 1.27 1.27)
					(thickness 0.15)
				)
				(justify left bottom)
				(hide yes)
			)
		)
		(pin "1"
		)
		(instances
			(project "sodimm-ddr5-tester"
				(path ""
					(reference "#PWR0428")
					(unit 1)
				)
			)
		)
	)
	(symbol
		(lib_id "antmicropower:+3V3")
		(at 173.99 236.22 0)
		(unit 1)
		(exclude_from_sim no)
		(in_bom yes)
		(on_board yes)
		(dnp no)
		(fields_autoplaced yes)
		(property "Reference" "#PWR0433"
			(at 173.99 240.03 0)
			(effects
				(font
					(size 1.27 1.27)
				)
				(hide yes)
			)
		)
		(property "Value" "+3V3"
			(at 170.815 233.68 0)
			(effects
				(font
					(size 1.27 1.27)
					(thickness 0.15)
				)
				(justify left bottom)
			)
		)
		(property "Footprint" ""
			(at 189.23 243.84 0)
			(effects
				(font
					(size 1.27 1.27)
					(thickness 0.15)
				)
				(justify left bottom)
				(hide yes)
			)
		)
		(property "Datasheet" ""
			(at 189.23 246.38 0)
			(effects
				(font
					(size 1.27 1.27)
					(thickness 0.15)
				)
				(justify left bottom)
				(hide yes)
			)
		)
		(property "Description" ""
			(at 173.99 236.22 0)
			(effects
				(font
					(size 1.27 1.27)
				)
			)
		)
		(property "Author" "Antmicro"
			(at 189.23 238.76 0)
			(effects
				(font
					(size 1.27 1.27)
					(thickness 0.15)
				)
				(justify left bottom)
				(hide yes)
			)
		)
		(property "License" "Apache-2.0"
			(at 189.23 241.3 0)
			(effects
				(font
					(size 1.27 1.27)
					(thickness 0.15)
				)
				(justify left bottom)
				(hide yes)
			)
		)
		(pin "1"
		)
		(instances
			(project "sodimm-ddr5-tester"
				(path ""
					(reference "#PWR0433")
					(unit 1)
				)
			)
		)
	)
	(symbol
		(lib_id "antmicropower:+3V3")
		(at 135.89 236.22 0)
		(unit 1)
		(exclude_from_sim no)
		(in_bom yes)
		(on_board yes)
		(dnp no)
		(fields_autoplaced yes)
		(property "Reference" "#PWR0435"
			(at 135.89 240.03 0)
			(effects
				(font
					(size 1.27 1.27)
				)
				(hide yes)
			)
		)
		(property "Value" "+3V3"
			(at 132.715 233.68 0)
			(effects
				(font
					(size 1.27 1.27)
					(thickness 0.15)
				)
				(justify left bottom)
			)
		)
		(property "Footprint" ""
			(at 151.13 243.84 0)
			(effects
				(font
					(size 1.27 1.27)
					(thickness 0.15)
				)
				(justify left bottom)
				(hide yes)
			)
		)
		(property "Datasheet" ""
			(at 151.13 246.38 0)
			(effects
				(font
					(size 1.27 1.27)
					(thickness 0.15)
				)
				(justify left bottom)
				(hide yes)
			)
		)
		(property "Description" ""
			(at 135.89 236.22 0)
			(effects
				(font
					(size 1.27 1.27)
				)
			)
		)
		(property "Author" "Antmicro"
			(at 151.13 238.76 0)
			(effects
				(font
					(size 1.27 1.27)
					(thickness 0.15)
				)
				(justify left bottom)
				(hide yes)
			)
		)
		(property "License" "Apache-2.0"
			(at 151.13 241.3 0)
			(effects
				(font
					(size 1.27 1.27)
					(thickness 0.15)
				)
				(justify left bottom)
				(hide yes)
			)
		)
		(pin "1"
		)
		(instances
			(project "sodimm-ddr5-tester"
				(path ""
					(reference "#PWR0435")
					(unit 1)
				)
			)
		)
	)
	(symbol
		(lib_id "antmicroTestPoints:TP_1mm_SMD")
		(at 225.425 252.095 180)
		(unit 1)
		(exclude_from_sim no)
		(in_bom yes)
		(on_board yes)
		(dnp no)
		(fields_autoplaced yes)
		(property "Reference" "TP23"
			(at 222.25 249.047 0)
			(effects
				(font
					(size 1.27 1.27)
				)
			)
		)
		(property "Value" "TP_1mm_SMD"
			(at 210.185 244.475 0)
			(effects
				(font
					(size 1.27 1.27)
					(thickness 0.15)
				)
				(justify left bottom)
				(hide yes)
			)
		)
		(property "Footprint" "antmicro-footprints:TP_SMD_1mm"
			(at 210.185 241.935 0)
			(effects
				(font
					(size 1.27 1.27)
					(thickness 0.15)
				)
				(justify left bottom)
				(hide yes)
			)
		)
		(property "Datasheet" ""
			(at 210.185 239.395 0)
			(effects
				(font
					(size 1.27 1.27)
					(thickness 0.15)
				)
				(justify left bottom)
				(hide yes)
			)
		)
		(property "Description" ""
			(at 225.425 252.095 0)
			(effects
				(font
					(size 1.27 1.27)
				)
			)
		)
		(property "MPN" ""
			(at 225.425 252.095 0)
			(effects
				(font
					(size 1.27 1.27)
				)
				(hide yes)
			)
		)
		(property "Manufacturer" ""
			(at 225.425 252.095 0)
			(effects
				(font
					(size 1.27 1.27)
				)
				(hide yes)
			)
		)
		(property "Author" "Antmicro"
			(at 210.185 236.855 0)
			(effects
				(font
					(size 1.27 1.27)
					(thickness 0.15)
				)
				(justify left bottom)
				(hide yes)
			)
		)
		(property "License" "Apache-2.0"
			(at 210.185 234.315 0)
			(effects
				(font
					(size 1.27 1.27)
					(thickness 0.15)
				)
				(justify left bottom)
				(hide yes)
			)
		)
		(pin "1"
		)
		(instances
			(project "sodimm-ddr5-tester"
				(path ""
					(reference "TP23")
					(unit 1)
				)
			)
		)
	)
	(symbol
		(lib_id "antmicroLEDIndicationDiscrete:LED_G_0603_KP-1608CGCK")
		(at 67.31 237.49 270)
		(unit 1)
		(exclude_from_sim no)
		(in_bom yes)
		(on_board yes)
		(dnp no)
		(property "Reference" "D6"
			(at 70.358 240.4694 90)
			(effects
				(font
					(size 1.27 1.27)
				)
				(justify left)
			)
		)
		(property "Value" "LED_G_0603_KP-1608CGCK"
			(at 83.058 242.951 90)
			(effects
				(font
					(size 1.27 1.27)
					(thickness 0.15)
				)
			)
		)
		(property "Footprint" "antmicro-footprints:LED_0603_1608Metric_G"
			(at 57.15 260.35 0)
			(effects
				(font
					(size 1.27 1.27)
					(thickness 0.15)
				)
				(justify left bottom)
				(hide yes)
			)
		)
		(property "Datasheet" "http://www.farnell.com/datasheets/2045956.pdf"
			(at 54.61 260.35 0)
			(effects
				(font
					(size 1.27 1.27)
					(thickness 0.15)
				)
				(justify left bottom)
				(hide yes)
			)
		)
		(property "Description" ""
			(at 67.31 237.49 0)
			(effects
				(font
					(size 1.27 1.27)
				)
			)
		)
		(property "MPN" "KP-1608CGCK"
			(at 70.358 242.9997 90)
			(effects
				(font
					(size 1.27 1.27)
					(thickness 0.15)
				)
				(justify left)
				(hide yes)
			)
		)
		(property "Manufacturer" "Kingbright"
			(at 49.53 260.35 0)
			(effects
				(font
					(size 1.27 1.27)
					(thickness 0.15)
				)
				(justify left bottom)
				(hide yes)
			)
		)
		(property "Author" "Antmicro"
			(at 46.99 260.35 0)
			(effects
				(font
					(size 1.27 1.27)
					(thickness 0.15)
				)
				(justify left bottom)
				(hide yes)
			)
		)
		(property "License" "Apache-2.0"
			(at 44.45 260.35 0)
			(effects
				(font
					(size 1.27 1.27)
					(thickness 0.15)
				)
				(justify left bottom)
				(hide yes)
			)
		)
		(pin "1"
		)
		(pin "2"
		)
		(instances
			(project "sodimm-ddr5-tester"
				(path ""
					(reference "D6")
					(unit 1)
				)
			)
		)
	)
	(symbol
		(lib_id "antmicropower:GND")
		(at 101.6 266.7 0)
		(unit 1)
		(exclude_from_sim no)
		(in_bom yes)
		(on_board yes)
		(dnp no)
		(property "Reference" "#PWR0430"
			(at 101.6 273.05 0)
			(effects
				(font
					(size 1.27 1.27)
				)
				(hide yes)
			)
		)
		(property "Value" "GND"
			(at 100.076 270.637 0)
			(effects
				(font
					(size 1.27 1.27)
					(thickness 0.15)
				)
				(justify left)
			)
		)
		(property "Footprint" ""
			(at 110.49 274.32 0)
			(effects
				(font
					(size 1.27 1.27)
					(thickness 0.15)
				)
				(justify left bottom)
				(hide yes)
			)
		)
		(property "Datasheet" ""
			(at 110.49 279.4 0)
			(effects
				(font
					(size 1.27 1.27)
					(thickness 0.15)
				)
				(justify left bottom)
				(hide yes)
			)
		)
		(property "Description" ""
			(at 110.49 281.94 0)
			(effects
				(font
					(size 1.27 1.27)
				)
				(justify left bottom)
				(hide yes)
			)
		)
		(property "Author" "Antmicro"
			(at 110.49 274.32 0)
			(effects
				(font
					(size 1.27 1.27)
					(thickness 0.15)
				)
				(justify left bottom)
				(hide yes)
			)
		)
		(property "License" "Apache-2.0"
			(at 110.49 276.86 0)
			(effects
				(font
					(size 1.27 1.27)
					(thickness 0.15)
				)
				(justify left bottom)
				(hide yes)
			)
		)
		(pin "1"
		)
		(instances
			(project "sodimm-ddr5-tester"
				(path ""
					(reference "#PWR0430")
					(unit 1)
				)
			)
		)
	)
	(symbol
		(lib_id "antmicroTransistorsFETsMOSFETsSingle:BSS138PW,115")
		(at 166.37 261.62 0)
		(unit 1)
		(exclude_from_sim no)
		(in_bom yes)
		(on_board yes)
		(dnp no)
		(fields_autoplaced yes)
		(property "Reference" "Q8"
			(at 177.8 257.81 0)
			(effects
				(font
					(size 1.27 1.27)
					(thickness 0.15)
				)
				(justify left)
			)
		)
		(property "Value" "BSS138PW,115"
			(at 189.23 270.51 0)
			(effects
				(font
					(size 1.27 1.27)
					(thickness 0.15)
				)
				(justify left bottom)
				(hide yes)
			)
		)
		(property "Footprint" "antmicro-footprints:SC70-3"
			(at 189.23 273.05 0)
			(effects
				(font
					(size 1.27 1.27)
					(thickness 0.15)
				)
				(justify left bottom)
				(hide yes)
			)
		)
		(property "Datasheet" "https://assets.nexperia.com/documents/data-sheet/BSS138PW.pdf"
			(at 189.23 275.59 0)
			(effects
				(font
					(size 1.27 1.27)
					(thickness 0.15)
				)
				(justify left bottom)
				(hide yes)
			)
		)
		(property "Description" "Power MOSFET, N Channel, 60 V, 320 mA, 0.9 ohm, SOT-323, Surface Mount"
			(at 189.23 288.29 0)
			(effects
				(font
					(size 1.27 1.27)
				)
				(justify left bottom)
				(hide yes)
			)
		)
		(property "MPN" "BSS138PW,115"
			(at 177.8 260.35 0)
			(effects
				(font
					(size 1.27 1.27)
					(thickness 0.15)
				)
				(justify left)
			)
		)
		(property "Manufacturer" "Nexperia"
			(at 189.23 280.67 0)
			(effects
				(font
					(size 1.27 1.27)
					(thickness 0.15)
				)
				(justify left bottom)
				(hide yes)
			)
		)
		(property "Author" "Antmicro"
			(at 189.23 283.21 0)
			(effects
				(font
					(size 1.27 1.27)
					(thickness 0.15)
				)
				(justify left bottom)
				(hide yes)
			)
		)
		(property "License" "Apache-2.0"
			(at 189.23 285.75 0)
			(effects
				(font
					(size 1.27 1.27)
					(thickness 0.15)
				)
				(justify left bottom)
				(hide yes)
			)
		)
		(pin "3"
		)
		(pin "2"
		)
		(pin "1"
		)
		(instances
			(project "sodimm-ddr5-tester"
				(path ""
					(reference "Q8")
					(unit 1)
				)
			)
		)
	)
	(symbol
		(lib_id "antmicroFPGAChips:XC7K160T-FFG676")
		(at 212.09 46.99 0)
		(unit 3)
		(exclude_from_sim no)
		(in_bom yes)
		(on_board yes)
		(dnp no)
		(fields_autoplaced yes)
		(property "Reference" "U4"
			(at 253.492 110.9294 0)
			(effects
				(font
					(size 1.27 1.27)
				)
				(justify left)
			)
		)
		(property "Value" "XC7K160T-FFG676"
			(at 253.492 113.4597 0)
			(effects
				(font
					(size 1.27 1.27)
					(thickness 0.15)
				)
				(justify left)
			)
		)
		(property "Footprint" "antmicro-footprints:BGA-676_27x27mm_Layout26x26_P1x1mm_FFG676"
			(at 280.67 49.53 0)
			(effects
				(font
					(size 1.27 1.27)
					(thickness 0.15)
				)
				(justify left bottom)
				(hide yes)
			)
		)
		(property "Datasheet" "https://docs.xilinx.com/v/u/en-US/ds180_7Series_Overview"
			(at 280.67 52.07 0)
			(effects
				(font
					(size 1.27 1.27)
					(thickness 0.15)
				)
				(justify left bottom)
				(hide yes)
			)
		)
		(property "Description" ""
			(at 212.09 46.99 0)
			(effects
				(font
					(size 1.27 1.27)
				)
			)
		)
		(property "MPN" "XC7K160T-FFG676"
			(at 212.09 46.99 0)
			(effects
				(font
					(size 1.27 1.27)
				)
				(hide yes)
			)
		)
		(property "Author" "Antmicro"
			(at 280.67 54.61 0)
			(effects
				(font
					(size 1.27 1.27)
					(thickness 0.15)
				)
				(justify left bottom)
				(hide yes)
			)
		)
		(property "License" "Apache-2.0"
			(at 280.67 57.15 0)
			(effects
				(font
					(size 1.27 1.27)
					(thickness 0.15)
				)
				(justify left bottom)
				(hide yes)
			)
		)
		(property "Manufacturer" "AMD-Xilinx"
			(at 212.09 46.99 0)
			(effects
				(font
					(size 1.27 1.27)
				)
				(hide yes)
			)
		)
		(pin "AA21"
		)
		(pin "AA22"
		)
		(pin "AA23"
		)
		(pin "AA24"
		)
		(pin "AA25"
		)
		(pin "AB21"
		)
		(pin "AB22"
		)
		(pin "AB24"
		)
		(pin "AB25"
		)
		(pin "AB26"
		)
		(pin "AC21"
		)
		(pin "AC22"
		)
		(pin "AC23"
		)
		(pin "AC24"
		)
		(pin "AC25"
		)
		(pin "AC26"
		)
		(pin "AD21"
		)
		(pin "AD22"
		)
		(pin "AD23"
		)
		(pin "AD24"
		)
		(pin "AD25"
		)
		(pin "AD26"
		)
		(pin "AE21"
		)
		(pin "AE22"
		)
		(pin "AE23"
		)
		(pin "AE25"
		)
		(pin "AE26"
		)
		(pin "AF22"
		)
		(pin "AF23"
		)
		(pin "AF24"
		)
		(pin "AF25"
		)
		(pin "AF26"
		)
		(pin "U21"
		)
		(pin "U22"
		)
		(pin "U23"
		)
		(pin "U24"
		)
		(pin "U25"
		)
		(pin "U26"
		)
		(pin "V20"
		)
		(pin "V21"
		)
		(pin "V22"
		)
		(pin "V23"
		)
		(pin "V24"
		)
		(pin "V26"
		)
		(pin "W20"
		)
		(pin "W21"
		)
		(pin "W23"
		)
		(pin "W24"
		)
		(pin "W25"
		)
		(pin "W26"
		)
		(pin "Y20"
		)
		(pin "Y21"
		)
		(pin "Y22"
		)
		(pin "Y23"
		)
		(pin "Y24"
		)
		(pin "Y25"
		)
		(pin "Y26"
		)
		(pin "K24"
		)
		(pin "K25"
		)
		(pin "K26"
		)
		(pin "L24"
		)
		(pin "L25"
		)
		(pin "M19"
		)
		(pin "M20"
		)
		(pin "M21"
		)
		(pin "M22"
		)
		(pin "M24"
		)
		(pin "M25"
		)
		(pin "M26"
		)
		(pin "N16"
		)
		(pin "N17"
		)
		(pin "N18"
		)
		(pin "N19"
		)
		(pin "N21"
		)
		(pin "N22"
		)
		(pin "N23"
		)
		(pin "N24"
		)
		(pin "N25"
		)
		(pin "N26"
		)
		(pin "P16"
		)
		(pin "P18"
		)
		(pin "P19"
		)
		(pin "P20"
		)
		(pin "P21"
		)
		(pin "P22"
		)
		(pin "P23"
		)
		(pin "P24"
		)
		(pin "P25"
		)
		(pin "P26"
		)
		(pin "R16"
		)
		(pin "R17"
		)
		(pin "R18"
		)
		(pin "R19"
		)
		(pin "R20"
		)
		(pin "R21"
		)
		(pin "R22"
		)
		(pin "R23"
		)
		(pin "R25"
		)
		(pin "R26"
		)
		(pin "T16"
		)
		(pin "T17"
		)
		(pin "T18"
		)
		(pin "T19"
		)
		(pin "T20"
		)
		(pin "T22"
		)
		(pin "T23"
		)
		(pin "T24"
		)
		(pin "T25"
		)
		(pin "T26"
		)
		(pin "U16"
		)
		(pin "U17"
		)
		(pin "U19"
		)
		(pin "U20"
		)
		(pin "A20"
		)
		(pin "A21"
		)
		(pin "A22"
		)
		(pin "A23"
		)
		(pin "A24"
		)
		(pin "A25"
		)
		(pin "B20"
		)
		(pin "B21"
		)
		(pin "B22"
		)
		(pin "B24"
		)
		(pin "B25"
		)
		(pin "B26"
		)
		(pin "C21"
		)
		(pin "C22"
		)
		(pin "C23"
		)
		(pin "C24"
		)
		(pin "C25"
		)
		(pin "C26"
		)
		(pin "D21"
		)
		(pin "D22"
		)
		(pin "D23"
		)
		(pin "D24"
		)
		(pin "D25"
		)
		(pin "D26"
		)
		(pin "E21"
		)
		(pin "E22"
		)
		(pin "E23"
		)
		(pin "E25"
		)
		(pin "E26"
		)
		(pin "F22"
		)
		(pin "F23"
		)
		(pin "F24"
		)
		(pin "F25"
		)
		(pin "F26"
		)
		(pin "G21"
		)
		(pin "G22"
		)
		(pin "G23"
		)
		(pin "G24"
		)
		(pin "G25"
		)
		(pin "G26"
		)
		(pin "H21"
		)
		(pin "H22"
		)
		(pin "H23"
		)
		(pin "H24"
		)
		(pin "H26"
		)
		(pin "J21"
		)
		(pin "J23"
		)
		(pin "J24"
		)
		(pin "J25"
		)
		(pin "J26"
		)
		(pin "K21"
		)
		(pin "K22"
		)
		(pin "K23"
		)
		(pin "L21"
		)
		(pin "L22"
		)
		(pin "L23"
		)
		(pin "A17"
		)
		(pin "A18"
		)
		(pin "A19"
		)
		(pin "B16"
		)
		(pin "B17"
		)
		(pin "B18"
		)
		(pin "B19"
		)
		(pin "C16"
		)
		(pin "C17"
		)
		(pin "C18"
		)
		(pin "C19"
		)
		(pin "D15"
		)
		(pin "D16"
		)
		(pin "D18"
		)
		(pin "D19"
		)
		(pin "D20"
		)
		(pin "E15"
		)
		(pin "E16"
		)
		(pin "E17"
		)
		(pin "E18"
		)
		(pin "E19"
		)
		(pin "E20"
		)
		(pin "F15"
		)
		(pin "F16"
		)
		(pin "F17"
		)
		(pin "F18"
		)
		(pin "F19"
		)
		(pin "F20"
		)
		(pin "G15"
		)
		(pin "G16"
		)
		(pin "G17"
		)
		(pin "G19"
		)
		(pin "G20"
		)
		(pin "H16"
		)
		(pin "H17"
		)
		(pin "H18"
		)
		(pin "H19"
		)
		(pin "H20"
		)
		(pin "J15"
		)
		(pin "J16"
		)
		(pin "J17"
		)
		(pin "J18"
		)
		(pin "J19"
		)
		(pin "J20"
		)
		(pin "K15"
		)
		(pin "K16"
		)
		(pin "K17"
		)
		(pin "K18"
		)
		(pin "K20"
		)
		(pin "L17"
		)
		(pin "L18"
		)
		(pin "L19"
		)
		(pin "L20"
		)
		(pin "M16"
		)
		(pin "M17"
		)
		(pin "M18"
		)
		(pin "A10"
		)
		(pin "A11"
		)
		(pin "A12"
		)
		(pin "A13"
		)
		(pin "A14"
		)
		(pin "A15"
		)
		(pin "A8"
		)
		(pin "A9"
		)
		(pin "B10"
		)
		(pin "B11"
		)
		(pin "B12"
		)
		(pin "B14"
		)
		(pin "B15"
		)
		(pin "B8"
		)
		(pin "B9"
		)
		(pin "C11"
		)
		(pin "C12"
		)
		(pin "C13"
		)
		(pin "C14"
		)
		(pin "C15"
		)
		(pin "C9"
		)
		(pin "D10"
		)
		(pin "D11"
		)
		(pin "D12"
		)
		(pin "D13"
		)
		(pin "D14"
		)
		(pin "D8"
		)
		(pin "D9"
		)
		(pin "E10"
		)
		(pin "E11"
		)
		(pin "E12"
		)
		(pin "E13"
		)
		(pin "E9"
		)
		(pin "F10"
		)
		(pin "F12"
		)
		(pin "F13"
		)
		(pin "F14"
		)
		(pin "F8"
		)
		(pin "F9"
		)
		(pin "G10"
		)
		(pin "G11"
		)
		(pin "G12"
		)
		(pin "G13"
		)
		(pin "G14"
		)
		(pin "G9"
		)
		(pin "H10"
		)
		(pin "H11"
		)
		(pin "H12"
		)
		(pin "H13"
		)
		(pin "H14"
		)
		(pin "H8"
		)
		(pin "H9"
		)
		(pin "J10"
		)
		(pin "J11"
		)
		(pin "J13"
		)
		(pin "J14"
		)
		(pin "J8"
		)
		(pin "AA14"
		)
		(pin "AA15"
		)
		(pin "AA17"
		)
		(pin "AA18"
		)
		(pin "AA19"
		)
		(pin "AA20"
		)
		(pin "AB14"
		)
		(pin "AB15"
		)
		(pin "AB16"
		)
		(pin "AB17"
		)
		(pin "AB18"
		)
		(pin "AB19"
		)
		(pin "AB20"
		)
		(pin "AC14"
		)
		(pin "AC15"
		)
		(pin "AC16"
		)
		(pin "AC17"
		)
		(pin "AC18"
		)
		(pin "AC19"
		)
		(pin "AD14"
		)
		(pin "AD15"
		)
		(pin "AD16"
		)
		(pin "AD18"
		)
		(pin "AD19"
		)
		(pin "AD20"
		)
		(pin "AE15"
		)
		(pin "AE16"
		)
		(pin "AE17"
		)
		(pin "AE18"
		)
		(pin "AE19"
		)
		(pin "AE20"
		)
		(pin "AF14"
		)
		(pin "AF15"
		)
		(pin "AF16"
		)
		(pin "AF17"
		)
		(pin "AF18"
		)
		(pin "AF19"
		)
		(pin "AF20"
		)
		(pin "V13"
		)
		(pin "V14"
		)
		(pin "V16"
		)
		(pin "V17"
		)
		(pin "V18"
		)
		(pin "V19"
		)
		(pin "W13"
		)
		(pin "W14"
		)
		(pin "W15"
		)
		(pin "W16"
		)
		(pin "W17"
		)
		(pin "W18"
		)
		(pin "W19"
		)
		(pin "Y14"
		)
		(pin "Y15"
		)
		(pin "Y16"
		)
		(pin "Y17"
		)
		(pin "Y18"
		)
		(pin "AA10"
		)
		(pin "AA11"
		)
		(pin "AA12"
		)
		(pin "AA13"
		)
		(pin "AA7"
		)
		(pin "AA8"
		)
		(pin "AA9"
		)
		(pin "AB10"
		)
		(pin "AB11"
		)
		(pin "AB12"
		)
		(pin "AB7"
		)
		(pin "AB8"
		)
		(pin "AB9"
		)
		(pin "AC11"
		)
		(pin "AC12"
		)
		(pin "AC13"
		)
		(pin "AC7"
		)
		(pin "AC8"
		)
		(pin "AC9"
		)
		(pin "AD10"
		)
		(pin "AD11"
		)
		(pin "AD12"
		)
		(pin "AD13"
		)
		(pin "AD8"
		)
		(pin "AD9"
		)
		(pin "AE10"
		)
		(pin "AE11"
		)
		(pin "AE12"
		)
		(pin "AE13"
		)
		(pin "AE7"
		)
		(pin "AE8"
		)
		(pin "AE9"
		)
		(pin "AF10"
		)
		(pin "AF12"
		)
		(pin "AF13"
		)
		(pin "AF7"
		)
		(pin "AF8"
		)
		(pin "AF9"
		)
		(pin "U9"
		)
		(pin "V10"
		)
		(pin "V11"
		)
		(pin "V12"
		)
		(pin "V7"
		)
		(pin "V8"
		)
		(pin "V9"
		)
		(pin "W10"
		)
		(pin "W11"
		)
		(pin "W7"
		)
		(pin "W8"
		)
		(pin "W9"
		)
		(pin "Y10"
		)
		(pin "Y11"
		)
		(pin "Y12"
		)
		(pin "Y13"
		)
		(pin "Y7"
		)
		(pin "Y8"
		)
		(pin "AA1"
		)
		(pin "AA2"
		)
		(pin "AA3"
		)
		(pin "AA4"
		)
		(pin "AA5"
		)
		(pin "AB1"
		)
		(pin "AB2"
		)
		(pin "AB4"
		)
		(pin "AB5"
		)
		(pin "AB6"
		)
		(pin "AC1"
		)
		(pin "AC2"
		)
		(pin "AC3"
		)
		(pin "AC4"
		)
		(pin "AC5"
		)
		(pin "AC6"
		)
		(pin "AD1"
		)
		(pin "AD2"
		)
		(pin "AD3"
		)
		(pin "AD4"
		)
		(pin "AD5"
		)
		(pin "AD6"
		)
		(pin "AE1"
		)
		(pin "AE2"
		)
		(pin "AE3"
		)
		(pin "AE5"
		)
		(pin "AE6"
		)
		(pin "AF2"
		)
		(pin "AF3"
		)
		(pin "AF4"
		)
		(pin "AF5"
		)
		(pin "AF6"
		)
		(pin "T7"
		)
		(pin "U1"
		)
		(pin "U2"
		)
		(pin "U3"
		)
		(pin "U4"
		)
		(pin "U5"
		)
		(pin "U6"
		)
		(pin "U7"
		)
		(pin "V1"
		)
		(pin "V2"
		)
		(pin "V3"
		)
		(pin "V4"
		)
		(pin "V6"
		)
		(pin "W1"
		)
		(pin "W3"
		)
		(pin "W4"
		)
		(pin "W5"
		)
		(pin "W6"
		)
		(pin "Y1"
		)
		(pin "Y2"
		)
		(pin "Y3"
		)
		(pin "Y4"
		)
		(pin "Y5"
		)
		(pin "Y6"
		)
		(pin "A3"
		)
		(pin "A4"
		)
		(pin "B1"
		)
		(pin "B2"
		)
		(pin "B5"
		)
		(pin "B6"
		)
		(pin "C3"
		)
		(pin "C4"
		)
		(pin "D1"
		)
		(pin "D2"
		)
		(pin "D5"
		)
		(pin "D6"
		)
		(pin "E3"
		)
		(pin "E4"
		)
		(pin "F1"
		)
		(pin "F2"
		)
		(pin "F5"
		)
		(pin "F6"
		)
		(pin "G3"
		)
		(pin "G4"
		)
		(pin "H1"
		)
		(pin "H2"
		)
		(pin "H5"
		)
		(pin "H6"
		)
		(pin "J3"
		)
		(pin "J4"
		)
		(pin "K1"
		)
		(pin "K2"
		)
		(pin "K5"
		)
		(pin "K6"
		)
		(pin "L3"
		)
		(pin "L4"
		)
		(pin "M1"
		)
		(pin "M2"
		)
		(pin "N3"
		)
		(pin "N4"
		)
		(pin "P1"
		)
		(pin "P2"
		)
		(pin "R3"
		)
		(pin "R4"
		)
		(pin "A1"
		)
		(pin "A16"
		)
		(pin "A2"
		)
		(pin "A26"
		)
		(pin "A5"
		)
		(pin "A6"
		)
		(pin "A7"
		)
		(pin "AA16"
		)
		(pin "AA26"
		)
		(pin "AA6"
		)
		(pin "AB13"
		)
		(pin "AB23"
		)
		(pin "AB3"
		)
		(pin "AC10"
		)
		(pin "AC20"
		)
		(pin "AD17"
		)
		(pin "AD7"
		)
		(pin "AE14"
		)
		(pin "AE24"
		)
		(pin "AE4"
		)
		(pin "AF1"
		)
		(pin "AF11"
		)
		(pin "AF21"
		)
		(pin "B13"
		)
		(pin "B23"
		)
		(pin "B3"
		)
		(pin "B4"
		)
		(pin "B7"
		)
		(pin "C1"
		)
		(pin "C10"
		)
		(pin "C2"
		)
		(pin "C20"
		)
		(pin "C5"
		)
		(pin "C6"
		)
		(pin "C7"
		)
		(pin "D17"
		)
		(pin "D3"
		)
		(pin "D4"
		)
		(pin "D7"
		)
		(pin "E1"
		)
		(pin "E14"
		)
		(pin "E2"
		)
		(pin "E24"
		)
		(pin "E5"
		)
		(pin "E6"
		)
		(pin "E7"
		)
		(pin "E8"
		)
		(pin "F11"
		)
		(pin "F21"
		)
		(pin "F3"
		)
		(pin "F4"
		)
		(pin "F7"
		)
		(pin "G1"
		)
		(pin "G18"
		)
		(pin "G2"
		)
		(pin "G5"
		)
		(pin "G6"
		)
		(pin "G8"
		)
		(pin "H15"
		)
		(pin "H25"
		)
		(pin "H3"
		)
		(pin "H4"
		)
		(pin "H7"
		)
		(pin "J1"
		)
		(pin "J12"
		)
		(pin "J2"
		)
		(pin "J22"
		)
		(pin "J5"
		)
		(pin "J6"
		)
		(pin "J9"
		)
		(pin "K10"
		)
		(pin "K11"
		)
		(pin "K12"
		)
		(pin "K13"
		)
		(pin "K14"
		)
		(pin "K19"
		)
		(pin "K3"
		)
		(pin "K4"
		)
		(pin "K7"
		)
		(pin "K8"
		)
		(pin "K9"
		)
		(pin "L1"
		)
		(pin "L10"
		)
		(pin "L11"
		)
		(pin "L12"
		)
		(pin "L13"
		)
		(pin "L14"
		)
		(pin "L15"
		)
		(pin "L16"
		)
		(pin "L2"
		)
		(pin "L26"
		)
		(pin "L5"
		)
		(pin "L6"
		)
		(pin "L9"
		)
		(pin "M10"
		)
		(pin "M11"
		)
		(pin "M12"
		)
		(pin "M13"
		)
		(pin "M14"
		)
		(pin "M15"
		)
		(pin "M23"
		)
		(pin "M3"
		)
		(pin "M4"
		)
		(pin "M5"
		)
		(pin "M6"
		)
		(pin "M7"
		)
		(pin "M8"
		)
		(pin "M9"
		)
		(pin "N1"
		)
		(pin "N10"
		)
		(pin "N13"
		)
		(pin "N14"
		)
		(pin "N15"
		)
		(pin "N2"
		)
		(pin "N20"
		)
		(pin "N5"
		)
		(pin "N6"
		)
		(pin "N7"
		)
		(pin "N9"
		)
		(pin "P10"
		)
		(pin "P13"
		)
		(pin "P14"
		)
		(pin "P15"
		)
		(pin "P17"
		)
		(pin "P3"
		)
		(pin "P4"
		)
		(pin "P8"
		)
		(pin "P9"
		)
		(pin "R1"
		)
		(pin "R10"
		)
		(pin "R13"
		)
		(pin "R14"
		)
		(pin "R15"
		)
		(pin "R2"
		)
		(pin "R24"
		)
		(pin "R5"
		)
		(pin "R8"
		)
		(pin "R9"
		)
		(pin "T1"
		)
		(pin "T10"
		)
		(pin "T11"
		)
		(pin "T12"
		)
		(pin "T13"
		)
		(pin "T14"
		)
		(pin "T15"
		)
		(pin "T21"
		)
		(pin "T3"
		)
		(pin "T4"
		)
		(pin "T8"
		)
		(pin "T9"
		)
		(pin "U10"
		)
		(pin "U11"
		)
		(pin "U12"
		)
		(pin "U13"
		)
		(pin "U14"
		)
		(pin "U15"
		)
		(pin "U18"
		)
		(pin "U8"
		)
		(pin "V15"
		)
		(pin "V25"
		)
		(pin "V5"
		)
		(pin "W12"
		)
		(pin "W2"
		)
		(pin "W22"
		)
		(pin "Y19"
		)
		(pin "Y9"
		)
		(pin "C8"
		)
		(pin "G7"
		)
		(pin "J7"
		)
		(pin "L7"
		)
		(pin "L8"
		)
		(pin "N11"
		)
		(pin "N12"
		)
		(pin "N8"
		)
		(pin "P11"
		)
		(pin "P12"
		)
		(pin "P5"
		)
		(pin "P6"
		)
		(pin "P7"
		)
		(pin "R11"
		)
		(pin "R12"
		)
		(pin "R6"
		)
		(pin "R7"
		)
		(pin "T2"
		)
		(pin "T5"
		)
		(pin "T6"
		)
		(instances
			(project "sodimm-ddr5-tester"
				(path ""
					(reference "U4")
					(unit 3)
				)
			)
		)
	)
	(symbol
		(lib_id "antmicroResistors0402:R_100R_0402")
		(at 230.505 242.697 270)
		(unit 1)
		(exclude_from_sim no)
		(in_bom yes)
		(on_board yes)
		(dnp no)
		(fields_autoplaced yes)
		(property "Reference" "R21"
			(at 233.045 243.967 90)
			(effects
				(font
					(size 1.27 1.27)
				)
				(justify left)
			)
		)
		(property "Value" "R_100R_0402"
			(at 217.805 263.017 0)
			(effects
				(font
					(size 1.27 1.27)
					(thickness 0.15)
				)
				(justify left bottom)
				(hide yes)
			)
		)
		(property "Footprint" "antmicro-footprints:R_0402_1005Metric"
			(at 215.265 263.017 0)
			(effects
				(font
					(size 1.27 1.27)
					(thickness 0.15)
				)
				(justify left bottom)
				(hide yes)
			)
		)
		(property "Datasheet" "https://www.bourns.com/docs/product-datasheets/cr.pdf"
			(at 212.725 263.017 0)
			(effects
				(font
					(size 1.27 1.27)
					(thickness 0.15)
				)
				(justify left bottom)
				(hide yes)
			)
		)
		(property "Description" ""
			(at 230.505 242.697 0)
			(effects
				(font
					(size 1.27 1.27)
				)
			)
		)
		(property "Manufacturer" "Bourns"
			(at 207.645 263.017 0)
			(effects
				(font
					(size 1.27 1.27)
					(thickness 0.15)
				)
				(justify left bottom)
				(hide yes)
			)
		)
		(property "MPN" "CR0402-FX-1000GLF"
			(at 210.185 263.017 0)
			(effects
				(font
					(size 1.27 1.27)
					(thickness 0.15)
				)
				(justify left bottom)
				(hide yes)
			)
		)
		(property "Val" "100R"
			(at 233.045 247.1419 90)
			(effects
				(font
					(size 1.27 1.27)
					(thickness 0.15)
				)
				(justify left)
			)
		)
		(property "License" "Apache-2.0"
			(at 205.105 263.017 0)
			(effects
				(font
					(size 1.27 1.27)
					(thickness 0.15)
				)
				(justify left bottom)
				(hide yes)
			)
		)
		(property "Author" "Antmicro"
			(at 202.565 263.017 0)
			(effects
				(font
					(size 1.27 1.27)
					(thickness 0.15)
				)
				(justify left bottom)
				(hide yes)
			)
		)
		(property "Tolerance" "1%"
			(at 220.345 263.017 0)
			(effects
				(font
					(size 1.27 1.27)
				)
				(justify left bottom)
				(hide yes)
			)
		)
		(pin "1"
		)
		(pin "2"
		)
		(instances
			(project "sodimm-ddr5-tester"
				(path ""
					(reference "R21")
					(unit 1)
				)
			)
		)
	)
	(symbol
		(lib_id "antmicroTransistorsFETsMOSFETsSingle:BSS138PW,115")
		(at 59.69 261.62 0)
		(unit 1)
		(exclude_from_sim no)
		(in_bom yes)
		(on_board yes)
		(dnp no)
		(property "Reference" "Q6"
			(at 69.596 257.81 0)
			(effects
				(font
					(size 1.27 1.27)
					(thickness 0.15)
				)
				(justify left)
			)
		)
		(property "Value" "BSS138PW,115"
			(at 82.55 270.51 0)
			(effects
				(font
					(size 1.27 1.27)
					(thickness 0.15)
				)
				(justify left bottom)
				(hide yes)
			)
		)
		(property "Footprint" "antmicro-footprints:SC70-3"
			(at 82.55 273.05 0)
			(effects
				(font
					(size 1.27 1.27)
					(thickness 0.15)
				)
				(justify left bottom)
				(hide yes)
			)
		)
		(property "Datasheet" "https://assets.nexperia.com/documents/data-sheet/BSS138PW.pdf"
			(at 82.55 275.59 0)
			(effects
				(font
					(size 1.27 1.27)
					(thickness 0.15)
				)
				(justify left bottom)
				(hide yes)
			)
		)
		(property "Description" "Power MOSFET, N Channel, 60 V, 320 mA, 0.9 ohm, SOT-323, Surface Mount"
			(at 82.55 288.29 0)
			(effects
				(font
					(size 1.27 1.27)
				)
				(justify left bottom)
				(hide yes)
			)
		)
		(property "MPN" "BSS138PW,115"
			(at 69.596 260.35 0)
			(effects
				(font
					(size 1.27 1.27)
					(thickness 0.15)
				)
				(justify left)
			)
		)
		(property "Manufacturer" "Nexperia"
			(at 82.55 280.67 0)
			(effects
				(font
					(size 1.27 1.27)
					(thickness 0.15)
				)
				(justify left bottom)
				(hide yes)
			)
		)
		(property "Author" "Antmicro"
			(at 82.55 283.21 0)
			(effects
				(font
					(size 1.27 1.27)
					(thickness 0.15)
				)
				(justify left bottom)
				(hide yes)
			)
		)
		(property "License" "Apache-2.0"
			(at 82.55 285.75 0)
			(effects
				(font
					(size 1.27 1.27)
					(thickness 0.15)
				)
				(justify left bottom)
				(hide yes)
			)
		)
		(pin "3"
		)
		(pin "2"
		)
		(pin "1"
		)
		(instances
			(project "sodimm-ddr5-tester"
				(path ""
					(reference "Q6")
					(unit 1)
				)
			)
		)
	)
	(symbol
		(lib_id "antmicropower:+3V3")
		(at 230.505 240.411 0)
		(unit 1)
		(exclude_from_sim no)
		(in_bom yes)
		(on_board yes)
		(dnp no)
		(property "Reference" "#PWR030"
			(at 230.505 244.221 0)
			(effects
				(font
					(size 1.27 1.27)
				)
				(hide yes)
			)
		)
		(property "Value" "+3V3"
			(at 227.33 237.871 0)
			(effects
				(font
					(size 1.27 1.27)
					(thickness 0.15)
				)
				(justify left bottom)
			)
		)
		(property "Footprint" ""
			(at 245.745 248.031 0)
			(effects
				(font
					(size 1.27 1.27)
					(thickness 0.15)
				)
				(justify left bottom)
				(hide yes)
			)
		)
		(property "Datasheet" ""
			(at 245.745 250.571 0)
			(effects
				(font
					(size 1.27 1.27)
					(thickness 0.15)
				)
				(justify left bottom)
				(hide yes)
			)
		)
		(property "Description" ""
			(at 230.505 240.411 0)
			(effects
				(font
					(size 1.27 1.27)
				)
			)
		)
		(property "Author" "Antmicro"
			(at 245.745 242.951 0)
			(effects
				(font
					(size 1.27 1.27)
					(thickness 0.15)
				)
				(justify left bottom)
				(hide yes)
			)
		)
		(property "License" "Apache-2.0"
			(at 245.745 245.491 0)
			(effects
				(font
					(size 1.27 1.27)
					(thickness 0.15)
				)
				(justify left bottom)
				(hide yes)
			)
		)
		(pin "1"
		)
		(instances
			(project "sodimm-ddr5-tester"
				(path ""
					(reference "#PWR030")
					(unit 1)
				)
			)
		)
	)
	(symbol
		(lib_id "antmicroLEDIndicationDiscrete:LED_G_0603_KP-1608CGCK")
		(at 135.89 237.49 270)
		(unit 1)
		(exclude_from_sim no)
		(in_bom yes)
		(on_board yes)
		(dnp no)
		(property "Reference" "D7"
			(at 138.938 240.4694 90)
			(effects
				(font
					(size 1.27 1.27)
				)
				(justify left)
			)
		)
		(property "Value" "LED_G_0603_KP-1608CGCK"
			(at 152.273 242.951 90)
			(effects
				(font
					(size 1.27 1.27)
					(thickness 0.15)
				)
			)
		)
		(property "Footprint" "antmicro-footprints:LED_0603_1608Metric_G"
			(at 125.73 260.35 0)
			(effects
				(font
					(size 1.27 1.27)
					(thickness 0.15)
				)
				(justify left bottom)
				(hide yes)
			)
		)
		(property "Datasheet" "http://www.farnell.com/datasheets/2045956.pdf"
			(at 123.19 260.35 0)
			(effects
				(font
					(size 1.27 1.27)
					(thickness 0.15)
				)
				(justify left bottom)
				(hide yes)
			)
		)
		(property "Description" ""
			(at 135.89 237.49 0)
			(effects
				(font
					(size 1.27 1.27)
				)
			)
		)
		(property "MPN" "KP-1608CGCK"
			(at 138.938 242.9997 90)
			(effects
				(font
					(size 1.27 1.27)
					(thickness 0.15)
				)
				(justify left)
				(hide yes)
			)
		)
		(property "Manufacturer" "Kingbright"
			(at 118.11 260.35 0)
			(effects
				(font
					(size 1.27 1.27)
					(thickness 0.15)
				)
				(justify left bottom)
				(hide yes)
			)
		)
		(property "Author" "Antmicro"
			(at 115.57 260.35 0)
			(effects
				(font
					(size 1.27 1.27)
					(thickness 0.15)
				)
				(justify left bottom)
				(hide yes)
			)
		)
		(property "License" "Apache-2.0"
			(at 113.03 260.35 0)
			(effects
				(font
					(size 1.27 1.27)
					(thickness 0.15)
				)
				(justify left bottom)
				(hide yes)
			)
		)
		(pin "1"
		)
		(pin "2"
		)
		(instances
			(project "sodimm-ddr5-tester"
				(path ""
					(reference "D7")
					(unit 1)
				)
			)
		)
	)
	(symbol
		(lib_id "antmicropower:GND")
		(at 67.31 266.7 0)
		(unit 1)
		(exclude_from_sim no)
		(in_bom yes)
		(on_board yes)
		(dnp no)
		(property "Reference" "#PWR0434"
			(at 67.31 273.05 0)
			(effects
				(font
					(size 1.27 1.27)
				)
				(hide yes)
			)
		)
		(property "Value" "GND"
			(at 65.786 270.637 0)
			(effects
				(font
					(size 1.27 1.27)
					(thickness 0.15)
				)
				(justify left)
			)
		)
		(property "Footprint" ""
			(at 76.2 274.32 0)
			(effects
				(font
					(size 1.27 1.27)
					(thickness 0.15)
				)
				(justify left bottom)
				(hide yes)
			)
		)
		(property "Datasheet" ""
			(at 76.2 279.4 0)
			(effects
				(font
					(size 1.27 1.27)
					(thickness 0.15)
				)
				(justify left bottom)
				(hide yes)
			)
		)
		(property "Description" ""
			(at 76.2 281.94 0)
			(effects
				(font
					(size 1.27 1.27)
				)
				(justify left bottom)
				(hide yes)
			)
		)
		(property "Author" "Antmicro"
			(at 76.2 274.32 0)
			(effects
				(font
					(size 1.27 1.27)
					(thickness 0.15)
				)
				(justify left bottom)
				(hide yes)
			)
		)
		(property "License" "Apache-2.0"
			(at 76.2 276.86 0)
			(effects
				(font
					(size 1.27 1.27)
					(thickness 0.15)
				)
				(justify left bottom)
				(hide yes)
			)
		)
		(pin "1"
		)
		(instances
			(project "sodimm-ddr5-tester"
				(path ""
					(reference "#PWR0434")
					(unit 1)
				)
			)
		)
	)
	(symbol
		(lib_id "antmicroResistors0402:R_330R_0402")
		(at 101.6 246.38 270)
		(unit 1)
		(exclude_from_sim no)
		(in_bom yes)
		(on_board yes)
		(dnp no)
		(fields_autoplaced yes)
		(property "Reference" "R41"
			(at 103.251 248.0894 90)
			(effects
				(font
					(size 1.27 1.27)
				)
				(justify left)
			)
		)
		(property "Value" "R_330R_0402"
			(at 88.9 266.7 0)
			(effects
				(font
					(size 1.27 1.27)
					(thickness 0.15)
				)
				(justify left bottom)
				(hide yes)
			)
		)
		(property "Footprint" "antmicro-footprints:R_0402_1005Metric"
			(at 86.36 266.7 0)
			(effects
				(font
					(size 1.27 1.27)
					(thickness 0.15)
				)
				(justify left bottom)
				(hide yes)
			)
		)
		(property "Datasheet" "https://www.bourns.com/docs/product-datasheets/cr.pdf"
			(at 83.82 266.7 0)
			(effects
				(font
					(size 1.27 1.27)
					(thickness 0.15)
				)
				(justify left bottom)
				(hide yes)
			)
		)
		(property "Description" ""
			(at 101.6 246.38 0)
			(effects
				(font
					(size 1.27 1.27)
				)
			)
		)
		(property "Manufacturer" "Bourns"
			(at 78.74 266.7 0)
			(effects
				(font
					(size 1.27 1.27)
					(thickness 0.15)
				)
				(justify left bottom)
				(hide yes)
			)
		)
		(property "MPN" "CR0402-FX-3300GLF"
			(at 81.28 266.7 0)
			(effects
				(font
					(size 1.27 1.27)
					(thickness 0.15)
				)
				(justify left bottom)
				(hide yes)
			)
		)
		(property "Val" "330R"
			(at 103.251 250.6197 90)
			(effects
				(font
					(size 1.27 1.27)
					(thickness 0.15)
				)
				(justify left)
			)
		)
		(property "License" "Apache-2.0"
			(at 76.2 266.7 0)
			(effects
				(font
					(size 1.27 1.27)
					(thickness 0.15)
				)
				(justify left bottom)
				(hide yes)
			)
		)
		(property "Author" "Antmicro"
			(at 73.66 266.7 0)
			(effects
				(font
					(size 1.27 1.27)
					(thickness 0.15)
				)
				(justify left bottom)
				(hide yes)
			)
		)
		(property "Tolerance" "1%"
			(at 91.44 266.7 0)
			(effects
				(font
					(size 1.27 1.27)
				)
				(justify left bottom)
				(hide yes)
			)
		)
		(pin "1"
		)
		(pin "2"
		)
		(instances
			(project "sodimm-ddr5-tester"
				(path ""
					(reference "R41")
					(unit 1)
				)
			)
		)
	)
	(symbol
		(lib_id "antmicroTransistorsFETsMOSFETsSingle:BSS138PW,115")
		(at 128.27 261.62 0)
		(unit 1)
		(exclude_from_sim no)
		(in_bom yes)
		(on_board yes)
		(dnp no)
		(property "Reference" "Q7"
			(at 138.176 257.81 0)
			(effects
				(font
					(size 1.27 1.27)
					(thickness 0.15)
				)
				(justify left)
			)
		)
		(property "Value" "BSS138PW,115"
			(at 151.13 270.51 0)
			(effects
				(font
					(size 1.27 1.27)
					(thickness 0.15)
				)
				(justify left bottom)
				(hide yes)
			)
		)
		(property "Footprint" "antmicro-footprints:SC70-3"
			(at 151.13 273.05 0)
			(effects
				(font
					(size 1.27 1.27)
					(thickness 0.15)
				)
				(justify left bottom)
				(hide yes)
			)
		)
		(property "Datasheet" "https://assets.nexperia.com/documents/data-sheet/BSS138PW.pdf"
			(at 151.13 275.59 0)
			(effects
				(font
					(size 1.27 1.27)
					(thickness 0.15)
				)
				(justify left bottom)
				(hide yes)
			)
		)
		(property "Description" "Power MOSFET, N Channel, 60 V, 320 mA, 0.9 ohm, SOT-323, Surface Mount"
			(at 151.13 288.29 0)
			(effects
				(font
					(size 1.27 1.27)
				)
				(justify left bottom)
				(hide yes)
			)
		)
		(property "MPN" "BSS138PW,115"
			(at 138.176 260.35 0)
			(effects
				(font
					(size 1.27 1.27)
					(thickness 0.15)
				)
				(justify left)
			)
		)
		(property "Manufacturer" "Nexperia"
			(at 151.13 280.67 0)
			(effects
				(font
					(size 1.27 1.27)
					(thickness 0.15)
				)
				(justify left bottom)
				(hide yes)
			)
		)
		(property "Author" "Antmicro"
			(at 151.13 283.21 0)
			(effects
				(font
					(size 1.27 1.27)
					(thickness 0.15)
				)
				(justify left bottom)
				(hide yes)
			)
		)
		(property "License" "Apache-2.0"
			(at 151.13 285.75 0)
			(effects
				(font
					(size 1.27 1.27)
					(thickness 0.15)
				)
				(justify left bottom)
				(hide yes)
			)
		)
		(pin "3"
		)
		(pin "2"
		)
		(pin "1"
		)
		(instances
			(project "sodimm-ddr5-tester"
				(path ""
					(reference "Q7")
					(unit 1)
				)
			)
		)
	)
	(symbol
		(lib_id "antmicropower:GND")
		(at 173.99 266.7 0)
		(unit 1)
		(exclude_from_sim no)
		(in_bom yes)
		(on_board yes)
		(dnp no)
		(property "Reference" "#PWR0431"
			(at 173.99 273.05 0)
			(effects
				(font
					(size 1.27 1.27)
				)
				(hide yes)
			)
		)
		(property "Value" "GND"
			(at 171.831 270.637 0)
			(effects
				(font
					(size 1.27 1.27)
					(thickness 0.15)
				)
				(justify left)
			)
		)
		(property "Footprint" ""
			(at 182.88 274.32 0)
			(effects
				(font
					(size 1.27 1.27)
					(thickness 0.15)
				)
				(justify left bottom)
				(hide yes)
			)
		)
		(property "Datasheet" ""
			(at 182.88 279.4 0)
			(effects
				(font
					(size 1.27 1.27)
					(thickness 0.15)
				)
				(justify left bottom)
				(hide yes)
			)
		)
		(property "Description" ""
			(at 182.88 281.94 0)
			(effects
				(font
					(size 1.27 1.27)
				)
				(justify left bottom)
				(hide yes)
			)
		)
		(property "Author" "Antmicro"
			(at 182.88 274.32 0)
			(effects
				(font
					(size 1.27 1.27)
					(thickness 0.15)
				)
				(justify left bottom)
				(hide yes)
			)
		)
		(property "License" "Apache-2.0"
			(at 182.88 276.86 0)
			(effects
				(font
					(size 1.27 1.27)
					(thickness 0.15)
				)
				(justify left bottom)
				(hide yes)
			)
		)
		(pin "1"
		)
		(instances
			(project "sodimm-ddr5-tester"
				(path ""
					(reference "#PWR0431")
					(unit 1)
				)
			)
		)
	)
	(symbol
		(lib_id "antmicroLEDIndicationDiscrete:LED_G_0603_KP-1608CGCK")
		(at 30.48 237.49 270)
		(unit 1)
		(exclude_from_sim no)
		(in_bom yes)
		(on_board yes)
		(dnp no)
		(property "Reference" "D4"
			(at 33.528 240.4694 90)
			(effects
				(font
					(size 1.27 1.27)
				)
				(justify left)
			)
		)
		(property "Value" "LED_G_0603_KP-1608CGCK"
			(at 46.99 242.57 90)
			(effects
				(font
					(size 1.27 1.27)
					(thickness 0.15)
				)
			)
		)
		(property "Footprint" "antmicro-footprints:LED_0603_1608Metric_G"
			(at 20.32 260.35 0)
			(effects
				(font
					(size 1.27 1.27)
					(thickness 0.15)
				)
				(justify left bottom)
				(hide yes)
			)
		)
		(property "Datasheet" "http://www.farnell.com/datasheets/2045956.pdf"
			(at 17.78 260.35 0)
			(effects
				(font
					(size 1.27 1.27)
					(thickness 0.15)
				)
				(justify left bottom)
				(hide yes)
			)
		)
		(property "Description" ""
			(at 30.48 237.49 0)
			(effects
				(font
					(size 1.27 1.27)
				)
			)
		)
		(property "MPN" "KP-1608CGCK"
			(at 33.528 242.9997 90)
			(effects
				(font
					(size 1.27 1.27)
					(thickness 0.15)
				)
				(justify left)
				(hide yes)
			)
		)
		(property "Manufacturer" "Kingbright"
			(at 12.7 260.35 0)
			(effects
				(font
					(size 1.27 1.27)
					(thickness 0.15)
				)
				(justify left bottom)
				(hide yes)
			)
		)
		(property "Author" "Antmicro"
			(at 10.16 260.35 0)
			(effects
				(font
					(size 1.27 1.27)
					(thickness 0.15)
				)
				(justify left bottom)
				(hide yes)
			)
		)
		(property "License" "Apache-2.0"
			(at 7.62 260.35 0)
			(effects
				(font
					(size 1.27 1.27)
					(thickness 0.15)
				)
				(justify left bottom)
				(hide yes)
			)
		)
		(pin "1"
		)
		(pin "2"
		)
		(instances
			(project "sodimm-ddr5-tester"
				(path ""
					(reference "D4")
					(unit 1)
				)
			)
		)
	)
	(symbol
		(lib_id "antmicropower:+3V3")
		(at 101.6 236.22 0)
		(unit 1)
		(exclude_from_sim no)
		(in_bom yes)
		(on_board yes)
		(dnp no)
		(fields_autoplaced yes)
		(property "Reference" "#PWR0426"
			(at 101.6 240.03 0)
			(effects
				(font
					(size 1.27 1.27)
				)
				(hide yes)
			)
		)
		(property "Value" "+3V3"
			(at 98.425 233.68 0)
			(effects
				(font
					(size 1.27 1.27)
					(thickness 0.15)
				)
				(justify left bottom)
			)
		)
		(property "Footprint" ""
			(at 116.84 243.84 0)
			(effects
				(font
					(size 1.27 1.27)
					(thickness 0.15)
				)
				(justify left bottom)
				(hide yes)
			)
		)
		(property "Datasheet" ""
			(at 116.84 246.38 0)
			(effects
				(font
					(size 1.27 1.27)
					(thickness 0.15)
				)
				(justify left bottom)
				(hide yes)
			)
		)
		(property "Description" ""
			(at 101.6 236.22 0)
			(effects
				(font
					(size 1.27 1.27)
				)
			)
		)
		(property "Author" "Antmicro"
			(at 116.84 238.76 0)
			(effects
				(font
					(size 1.27 1.27)
					(thickness 0.15)
				)
				(justify left bottom)
				(hide yes)
			)
		)
		(property "License" "Apache-2.0"
			(at 116.84 241.3 0)
			(effects
				(font
					(size 1.27 1.27)
					(thickness 0.15)
				)
				(justify left bottom)
				(hide yes)
			)
		)
		(pin "1"
		)
		(instances
			(project "sodimm-ddr5-tester"
				(path ""
					(reference "#PWR0426")
					(unit 1)
				)
			)
		)
	)
	(symbol
		(lib_id "antmicroTransistorsFETsMOSFETsSingle:BSS138PW,115")
		(at 93.98 261.62 0)
		(unit 1)
		(exclude_from_sim no)
		(in_bom yes)
		(on_board yes)
		(dnp no)
		(property "Reference" "Q5"
			(at 103.886 257.81 0)
			(effects
				(font
					(size 1.27 1.27)
					(thickness 0.15)
				)
				(justify left)
			)
		)
		(property "Value" "BSS138PW,115"
			(at 116.84 270.51 0)
			(effects
				(font
					(size 1.27 1.27)
					(thickness 0.15)
				)
				(justify left bottom)
				(hide yes)
			)
		)
		(property "Footprint" "antmicro-footprints:SC70-3"
			(at 116.84 273.05 0)
			(effects
				(font
					(size 1.27 1.27)
					(thickness 0.15)
				)
				(justify left bottom)
				(hide yes)
			)
		)
		(property "Datasheet" "https://assets.nexperia.com/documents/data-sheet/BSS138PW.pdf"
			(at 116.84 275.59 0)
			(effects
				(font
					(size 1.27 1.27)
					(thickness 0.15)
				)
				(justify left bottom)
				(hide yes)
			)
		)
		(property "Description" "Power MOSFET, N Channel, 60 V, 320 mA, 0.9 ohm, SOT-323, Surface Mount"
			(at 116.84 288.29 0)
			(effects
				(font
					(size 1.27 1.27)
				)
				(justify left bottom)
				(hide yes)
			)
		)
		(property "MPN" "BSS138PW,115"
			(at 103.886 260.35 0)
			(effects
				(font
					(size 1.27 1.27)
					(thickness 0.15)
				)
				(justify left)
			)
		)
		(property "Manufacturer" "Nexperia"
			(at 116.84 280.67 0)
			(effects
				(font
					(size 1.27 1.27)
					(thickness 0.15)
				)
				(justify left bottom)
				(hide yes)
			)
		)
		(property "Author" "Antmicro"
			(at 116.84 283.21 0)
			(effects
				(font
					(size 1.27 1.27)
					(thickness 0.15)
				)
				(justify left bottom)
				(hide yes)
			)
		)
		(property "License" "Apache-2.0"
			(at 116.84 285.75 0)
			(effects
				(font
					(size 1.27 1.27)
					(thickness 0.15)
				)
				(justify left bottom)
				(hide yes)
			)
		)
		(pin "3"
		)
		(pin "2"
		)
		(pin "1"
		)
		(instances
			(project "sodimm-ddr5-tester"
				(path ""
					(reference "Q5")
					(unit 1)
				)
			)
		)
	)
	(symbol
		(lib_id "antmicropower:GND")
		(at 135.89 266.7 0)
		(unit 1)
		(exclude_from_sim no)
		(in_bom yes)
		(on_board yes)
		(dnp no)
		(property "Reference" "#PWR0432"
			(at 135.89 273.05 0)
			(effects
				(font
					(size 1.27 1.27)
				)
				(hide yes)
			)
		)
		(property "Value" "GND"
			(at 134.366 270.637 0)
			(effects
				(font
					(size 1.27 1.27)
					(thickness 0.15)
				)
				(justify left)
			)
		)
		(property "Footprint" ""
			(at 144.78 274.32 0)
			(effects
				(font
					(size 1.27 1.27)
					(thickness 0.15)
				)
				(justify left bottom)
				(hide yes)
			)
		)
		(property "Datasheet" ""
			(at 144.78 279.4 0)
			(effects
				(font
					(size 1.27 1.27)
					(thickness 0.15)
				)
				(justify left bottom)
				(hide yes)
			)
		)
		(property "Description" ""
			(at 144.78 281.94 0)
			(effects
				(font
					(size 1.27 1.27)
				)
				(justify left bottom)
				(hide yes)
			)
		)
		(property "Author" "Antmicro"
			(at 144.78 274.32 0)
			(effects
				(font
					(size 1.27 1.27)
					(thickness 0.15)
				)
				(justify left bottom)
				(hide yes)
			)
		)
		(property "License" "Apache-2.0"
			(at 144.78 276.86 0)
			(effects
				(font
					(size 1.27 1.27)
					(thickness 0.15)
				)
				(justify left bottom)
				(hide yes)
			)
		)
		(pin "1"
		)
		(instances
			(project "sodimm-ddr5-tester"
				(path ""
					(reference "#PWR0432")
					(unit 1)
				)
			)
		)
	)
	(symbol
		(lib_id "antmicroResistors0402:R_330R_0402")
		(at 30.48 246.38 270)
		(unit 1)
		(exclude_from_sim no)
		(in_bom yes)
		(on_board yes)
		(dnp no)
		(fields_autoplaced yes)
		(property "Reference" "R40"
			(at 32.131 248.0894 90)
			(effects
				(font
					(size 1.27 1.27)
				)
				(justify left)
			)
		)
		(property "Value" "R_330R_0402"
			(at 17.78 266.7 0)
			(effects
				(font
					(size 1.27 1.27)
					(thickness 0.15)
				)
				(justify left bottom)
				(hide yes)
			)
		)
		(property "Footprint" "antmicro-footprints:R_0402_1005Metric"
			(at 15.24 266.7 0)
			(effects
				(font
					(size 1.27 1.27)
					(thickness 0.15)
				)
				(justify left bottom)
				(hide yes)
			)
		)
		(property "Datasheet" "https://www.bourns.com/docs/product-datasheets/cr.pdf"
			(at 12.7 266.7 0)
			(effects
				(font
					(size 1.27 1.27)
					(thickness 0.15)
				)
				(justify left bottom)
				(hide yes)
			)
		)
		(property "Description" ""
			(at 30.48 246.38 0)
			(effects
				(font
					(size 1.27 1.27)
				)
			)
		)
		(property "Manufacturer" "Bourns"
			(at 7.62 266.7 0)
			(effects
				(font
					(size 1.27 1.27)
					(thickness 0.15)
				)
				(justify left bottom)
				(hide yes)
			)
		)
		(property "MPN" "CR0402-FX-3300GLF"
			(at 10.16 266.7 0)
			(effects
				(font
					(size 1.27 1.27)
					(thickness 0.15)
				)
				(justify left bottom)
				(hide yes)
			)
		)
		(property "Val" "330R"
			(at 32.131 250.6197 90)
			(effects
				(font
					(size 1.27 1.27)
					(thickness 0.15)
				)
				(justify left)
			)
		)
		(property "License" "Apache-2.0"
			(at 5.08 266.7 0)
			(effects
				(font
					(size 1.27 1.27)
					(thickness 0.15)
				)
				(justify left bottom)
				(hide yes)
			)
		)
		(property "Author" "Antmicro"
			(at 2.54 266.7 0)
			(effects
				(font
					(size 1.27 1.27)
					(thickness 0.15)
				)
				(justify left bottom)
				(hide yes)
			)
		)
		(property "Tolerance" "1%"
			(at 20.32 266.7 0)
			(effects
				(font
					(size 1.27 1.27)
				)
				(justify left bottom)
				(hide yes)
			)
		)
		(pin "1"
		)
		(pin "2"
		)
		(instances
			(project "sodimm-ddr5-tester"
				(path ""
					(reference "R40")
					(unit 1)
				)
			)
		)
	)
	(symbol
		(lib_id "antmicropower:+3V3")
		(at 67.31 236.22 0)
		(unit 1)
		(exclude_from_sim no)
		(in_bom yes)
		(on_board yes)
		(dnp no)
		(property "Reference" "#PWR0429"
			(at 67.31 240.03 0)
			(effects
				(font
					(size 1.27 1.27)
				)
				(hide yes)
			)
		)
		(property "Value" "+3V3"
			(at 64.135 233.68 0)
			(effects
				(font
					(size 1.27 1.27)
					(thickness 0.15)
				)
				(justify left bottom)
			)
		)
		(property "Footprint" ""
			(at 82.55 243.84 0)
			(effects
				(font
					(size 1.27 1.27)
					(thickness 0.15)
				)
				(justify left bottom)
				(hide yes)
			)
		)
		(property "Datasheet" ""
			(at 82.55 246.38 0)
			(effects
				(font
					(size 1.27 1.27)
					(thickness 0.15)
				)
				(justify left bottom)
				(hide yes)
			)
		)
		(property "Description" ""
			(at 67.31 236.22 0)
			(effects
				(font
					(size 1.27 1.27)
				)
			)
		)
		(property "Author" "Antmicro"
			(at 82.55 238.76 0)
			(effects
				(font
					(size 1.27 1.27)
					(thickness 0.15)
				)
				(justify left bottom)
				(hide yes)
			)
		)
		(property "License" "Apache-2.0"
			(at 82.55 241.3 0)
			(effects
				(font
					(size 1.27 1.27)
					(thickness 0.15)
				)
				(justify left bottom)
				(hide yes)
			)
		)
		(pin "1"
		)
		(instances
			(project "sodimm-ddr5-tester"
				(path ""
					(reference "#PWR0429")
					(unit 1)
				)
			)
		)
	)
	(symbol
		(lib_id "antmicroLEDIndicationDiscrete:LED_G_0603_KP-1608CGCK")
		(at 101.6 237.49 270)
		(unit 1)
		(exclude_from_sim no)
		(in_bom yes)
		(on_board yes)
		(dnp no)
		(property "Reference" "D5"
			(at 104.648 240.4694 90)
			(effects
				(font
					(size 1.27 1.27)
				)
				(justify left)
			)
		)
		(property "Value" "LED_G_0603_KP-1608CGCK"
			(at 117.983 242.951 90)
			(effects
				(font
					(size 1.27 1.27)
					(thickness 0.15)
				)
			)
		)
		(property "Footprint" "antmicro-footprints:LED_0603_1608Metric_G"
			(at 91.44 260.35 0)
			(effects
				(font
					(size 1.27 1.27)
					(thickness 0.15)
				)
				(justify left bottom)
				(hide yes)
			)
		)
		(property "Datasheet" "http://www.farnell.com/datasheets/2045956.pdf"
			(at 88.9 260.35 0)
			(effects
				(font
					(size 1.27 1.27)
					(thickness 0.15)
				)
				(justify left bottom)
				(hide yes)
			)
		)
		(property "Description" ""
			(at 101.6 237.49 0)
			(effects
				(font
					(size 1.27 1.27)
				)
			)
		)
		(property "MPN" "KP-1608CGCK"
			(at 104.648 242.9997 90)
			(effects
				(font
					(size 1.27 1.27)
					(thickness 0.15)
				)
				(justify left)
				(hide yes)
			)
		)
		(property "Manufacturer" "Kingbright"
			(at 83.82 260.35 0)
			(effects
				(font
					(size 1.27 1.27)
					(thickness 0.15)
				)
				(justify left bottom)
				(hide yes)
			)
		)
		(property "Author" "Antmicro"
			(at 81.28 260.35 0)
			(effects
				(font
					(size 1.27 1.27)
					(thickness 0.15)
				)
				(justify left bottom)
				(hide yes)
			)
		)
		(property "License" "Apache-2.0"
			(at 78.74 260.35 0)
			(effects
				(font
					(size 1.27 1.27)
					(thickness 0.15)
				)
				(justify left bottom)
				(hide yes)
			)
		)
		(pin "1"
		)
		(pin "2"
		)
		(instances
			(project "sodimm-ddr5-tester"
				(path ""
					(reference "D5")
					(unit 1)
				)
			)
		)
	)
	(symbol
		(lib_id "antmicropower:GND")
		(at 230.505 260.223 0)
		(unit 1)
		(exclude_from_sim no)
		(in_bom yes)
		(on_board yes)
		(dnp no)
		(fields_autoplaced yes)
		(property "Reference" "#PWR031"
			(at 230.505 266.573 0)
			(effects
				(font
					(size 1.27 1.27)
				)
				(hide yes)
			)
		)
		(property "Value" "GND"
			(at 232.41 261.493 0)
			(effects
				(font
					(size 1.27 1.27)
					(thickness 0.15)
				)
				(justify left)
			)
		)
		(property "Footprint" ""
			(at 239.395 267.843 0)
			(effects
				(font
					(size 1.27 1.27)
					(thickness 0.15)
				)
				(justify left bottom)
				(hide yes)
			)
		)
		(property "Datasheet" ""
			(at 239.395 272.923 0)
			(effects
				(font
					(size 1.27 1.27)
					(thickness 0.15)
				)
				(justify left bottom)
				(hide yes)
			)
		)
		(property "Description" ""
			(at 239.395 275.463 0)
			(effects
				(font
					(size 1.27 1.27)
				)
				(justify left bottom)
				(hide yes)
			)
		)
		(property "Author" "Antmicro"
			(at 239.395 267.843 0)
			(effects
				(font
					(size 1.27 1.27)
					(thickness 0.15)
				)
				(justify left bottom)
				(hide yes)
			)
		)
		(property "License" "Apache-2.0"
			(at 239.395 270.383 0)
			(effects
				(font
					(size 1.27 1.27)
					(thickness 0.15)
				)
				(justify left bottom)
				(hide yes)
			)
		)
		(pin "1"
		)
		(instances
			(project "sodimm-ddr5-tester"
				(path ""
					(reference "#PWR031")
					(unit 1)
				)
			)
		)
	)
	(symbol
		(lib_id "antmicroResistors0402:R_330R_0402")
		(at 67.31 246.38 270)
		(unit 1)
		(exclude_from_sim no)
		(in_bom yes)
		(on_board yes)
		(dnp no)
		(fields_autoplaced yes)
		(property "Reference" "R42"
			(at 68.961 248.0894 90)
			(effects
				(font
					(size 1.27 1.27)
				)
				(justify left)
			)
		)
		(property "Value" "R_330R_0402"
			(at 54.61 266.7 0)
			(effects
				(font
					(size 1.27 1.27)
					(thickness 0.15)
				)
				(justify left bottom)
				(hide yes)
			)
		)
		(property "Footprint" "antmicro-footprints:R_0402_1005Metric"
			(at 52.07 266.7 0)
			(effects
				(font
					(size 1.27 1.27)
					(thickness 0.15)
				)
				(justify left bottom)
				(hide yes)
			)
		)
		(property "Datasheet" "https://www.bourns.com/docs/product-datasheets/cr.pdf"
			(at 49.53 266.7 0)
			(effects
				(font
					(size 1.27 1.27)
					(thickness 0.15)
				)
				(justify left bottom)
				(hide yes)
			)
		)
		(property "Description" ""
			(at 67.31 246.38 0)
			(effects
				(font
					(size 1.27 1.27)
				)
			)
		)
		(property "Manufacturer" "Bourns"
			(at 44.45 266.7 0)
			(effects
				(font
					(size 1.27 1.27)
					(thickness 0.15)
				)
				(justify left bottom)
				(hide yes)
			)
		)
		(property "MPN" "CR0402-FX-3300GLF"
			(at 46.99 266.7 0)
			(effects
				(font
					(size 1.27 1.27)
					(thickness 0.15)
				)
				(justify left bottom)
				(hide yes)
			)
		)
		(property "Val" "330R"
			(at 68.961 250.6197 90)
			(effects
				(font
					(size 1.27 1.27)
					(thickness 0.15)
				)
				(justify left)
			)
		)
		(property "License" "Apache-2.0"
			(at 41.91 266.7 0)
			(effects
				(font
					(size 1.27 1.27)
					(thickness 0.15)
				)
				(justify left bottom)
				(hide yes)
			)
		)
		(property "Author" "Antmicro"
			(at 39.37 266.7 0)
			(effects
				(font
					(size 1.27 1.27)
					(thickness 0.15)
				)
				(justify left bottom)
				(hide yes)
			)
		)
		(property "Tolerance" "1%"
			(at 57.15 266.7 0)
			(effects
				(font
					(size 1.27 1.27)
				)
				(justify left bottom)
				(hide yes)
			)
		)
		(pin "1"
		)
		(pin "2"
		)
		(instances
			(project "sodimm-ddr5-tester"
				(path ""
					(reference "R42")
					(unit 1)
				)
			)
		)
	)
	(symbol
		(lib_id "antmicroLEDIndicationDiscrete:LED_G_0603_KP-1608CGCK")
		(at 173.99 237.49 270)
		(unit 1)
		(exclude_from_sim no)
		(in_bom yes)
		(on_board yes)
		(dnp no)
		(property "Reference" "D8"
			(at 177.038 240.4694 90)
			(effects
				(font
					(size 1.27 1.27)
				)
				(justify left)
			)
		)
		(property "Value" "LED_G_0603_KP-1608CGCK"
			(at 189.738 242.951 90)
			(effects
				(font
					(size 1.27 1.27)
					(thickness 0.15)
				)
			)
		)
		(property "Footprint" "antmicro-footprints:LED_0603_1608Metric_G"
			(at 163.83 260.35 0)
			(effects
				(font
					(size 1.27 1.27)
					(thickness 0.15)
				)
				(justify left bottom)
				(hide yes)
			)
		)
		(property "Datasheet" "http://www.farnell.com/datasheets/2045956.pdf"
			(at 161.29 260.35 0)
			(effects
				(font
					(size 1.27 1.27)
					(thickness 0.15)
				)
				(justify left bottom)
				(hide yes)
			)
		)
		(property "Description" ""
			(at 173.99 237.49 0)
			(effects
				(font
					(size 1.27 1.27)
				)
			)
		)
		(property "MPN" "KP-1608CGCK"
			(at 177.038 242.9997 90)
			(effects
				(font
					(size 1.27 1.27)
					(thickness 0.15)
				)
				(justify left)
				(hide yes)
			)
		)
		(property "Manufacturer" "Kingbright"
			(at 156.21 260.35 0)
			(effects
				(font
					(size 1.27 1.27)
					(thickness 0.15)
				)
				(justify left bottom)
				(hide yes)
			)
		)
		(property "Author" "Antmicro"
			(at 153.67 260.35 0)
			(effects
				(font
					(size 1.27 1.27)
					(thickness 0.15)
				)
				(justify left bottom)
				(hide yes)
			)
		)
		(property "License" "Apache-2.0"
			(at 151.13 260.35 0)
			(effects
				(font
					(size 1.27 1.27)
					(thickness 0.15)
				)
				(justify left bottom)
				(hide yes)
			)
		)
		(pin "1"
		)
		(pin "2"
		)
		(instances
			(project "sodimm-ddr5-tester"
				(path ""
					(reference "D8")
					(unit 1)
				)
			)
		)
	)
)
